FILE_TYPE = MACRO_DRAWING;
SET COLOR_WIRE YELLOW;
SET COLOR_PROP ORANGE;
SET COLOR_DOT WHITE;
SET COLOR_ARC YELLOW;
SET COLOR_BODY GREEN;
SET COLOR_NOTE PURPLE;
SET PROP_DISPLAY VALUE;
SET PAGE_NUMBER P465;
FORCEADD Q_RES..1
(-7700 3525);
FORCEPROP 1 LAST LOCATION R894
J 0
(-7975 3525);
DISPLAY 0.787234 (-7975 3525);
FORCEPROP 2 LAST SEC 1
J 0
(-7750 3725);
DISPLAY 0.680851 (-7750 3725);
PAINT MONO (-7750 3725);
DISPLAY INVISIBLE (-7750 3725);
FORCEPROP 1 LASTPIN (-7800 3525) $PN 1
J 0
(-7788 3537);
DISPLAY 0.787234 (-7788 3537);
PAINT MONO (-7788 3537);
FORCEPROP 1 LASTPIN (-7600 3525) $PN 2
J 0
(-7638 3537);
DISPLAY 0.787234 (-7638 3537);
PAINT MONO (-7638 3537);
FORCEPROP 1 LAST WATTAGE 1/16W
J 2
(-7700 3425);
DISPLAY 0.638298 (-7700 3425);
FORCEPROP 1 LAST PACK_TYPE 0402LF
J 0
(-7850 3475);
DISPLAY 0.638298 (-7850 3475);
FORCEPROP 1 LAST TOLERANCE 5%
J 0
(-7650 3475);
DISPLAY 0.638298 (-7650 3475);
FORCEPROP 1 LAST MATERIAL EMPTY
J 0
(-7675 3425);
DISPLAY 0.638298 (-7675 3425);
FORCEPROP 1 LAST VALUE 0
J 2
(-7550 3550);
DISPLAY 0.638298 (-7550 3550);
FORCEPROP 2 LAST CDS_LIB pure_quanta
J 0
(-7700 3525);
DISPLAY INVISIBLE (-7700 3525);
FORCEPROP 2 LAST SEC_TYPE 0402LF
J 0
(-7750 3725);
DISPLAY 0.680851 (-7750 3725);
DISPLAY INVISIBLE (-7750 3725);
FORCEPROP 1 LAST PATH I1
J 0
(-7750 3675);
DISPLAY 0.978723 (-7750 3675);
PAINT WHITE (-7750 3675);
DISPLAY INVISIBLE (-7750 3675);
FORCEPROP 1 LAST PART_NUMBER CS00002JB13
J 0
(-7750 3625);
DISPLAY 0.978723 (-7750 3625);
DISPLAY INVISIBLE (-7750 3625);
FORCEADD Q_INDUCTOR..1
(-7775 4425);
FORCEPROP 1 LAST LOCATION L9
J 0
(-7900 4585);
DISPLAY 0.723404 (-7900 4585);
PAINT GREEN (-7900 4585);
FORCEPROP 0 LAST $SEC 1
J 0
(-7900 4675);
DISPLAY 0.680851 (-7900 4675);
PAINT MONO (-7900 4675);
DISPLAY INVISIBLE (-7900 4675);
FORCEPROP 0 LAST CDS_SEC 1
J 0
(-7900 4675);
DISPLAY 0.680851 (-7900 4675);
DISPLAY INVISIBLE (-7900 4675);
FORCEPROP 0 LASTPIN (-7875 4400) $PN 1
J 2
(-7885 4410);
DISPLAY 0.680851 (-7885 4410);
PAINT MONO (-7885 4410);
FORCEPROP 0 LASTPIN (-7675 4400) $PN 2
J 0
(-7665 4410);
DISPLAY 0.680851 (-7665 4410);
PAINT MONO (-7665 4410);
FORCEPROP 2 LAST VALUE BLM21SN300SN1D/5A
J 0
(-8025 4325);
DISPLAY 0.680851 (-8025 4325);
FORCEPROP 2 LAST PACK_TYPE SMLF
J 0
(-7900 4625);
DISPLAY 0.680851 (-7900 4625);
FORCEPROP 1 LAST MATERIAL IND
J 0
(-7900 4480);
DISPLAY 0.723404 (-7900 4480);
PAINT GREEN (-7900 4480);
FORCEPROP 2 LAST CDS_LIB pure_quanta
J 0
(-7775 4425);
DISPLAY INVISIBLE (-7775 4425);
FORCEPROP 1 LAST NEEDS_NO_SIZE TRUE
J 0
(-7775 4425);
DISPLAY 0.468085 (-7775 4425);
PAINT GREEN (-7775 4425);
DISPLAY INVISIBLE (-7775 4425);
FORCEPROP 1 LAST PATH I11
J 0
(-7700 4480);
DISPLAY 0.723404 (-7700 4480);
PAINT GREEN (-7700 4480);
DISPLAY INVISIBLE (-7700 4480);
FORCEPROP 1 LAST PART_NUMBER CX300SN1000
J 0
(-7900 4535);
DISPLAY 0.723404 (-7900 4535);
PAINT GREEN (-7900 4535);
DISPLAY INVISIBLE (-7900 4535);
FORCEADD P1V0..1
(-7300 4625);
FORCEPROP 3 LASTPIN (-7300 4575) SIG_NAME P1V8_CPU1_RT3_1A\g
J 0
(-7290 4585);
DISPLAY 0.659574 (-7290 4585);
PAINT MONO (-7290 4585);
DISPLAY INVISIBLE (-7290 4585);
FORCEPROP 1 LAST HDL_POWER P1V8_CPU1_RT3_1A
J 1
(-7300 4675);
DISPLAY 0.489362 (-7300 4675);
PAINT SKYBLUE (-7300 4675);
FORCEPROP 2 LAST CDS_LIB pure_quanta_power
J 0
(-7300 4625);
DISPLAY INVISIBLE (-7300 4625);
FORCEPROP 1 LAST PATH I12
J 0
(-7250 4650);
DISPLAY 0.872340 (-7250 4650);
PAINT AQUA (-7250 4650);
DISPLAY INVISIBLE (-7250 4650);
FORCEADD P1V0..1
(-8150 5250);
FORCEPROP 3 LASTPIN (-8150 5200) SIG_NAME P1V8_CPU1_RT_1D\g
J 0
(-8140 5210);
DISPLAY 0.659574 (-8140 5210);
PAINT MONO (-8140 5210);
DISPLAY INVISIBLE (-8140 5210);
FORCEPROP 1 LAST HDL_POWER P1V8_CPU1_RT_1D
J 1
(-8150 5300);
DISPLAY 0.489362 (-8150 5300);
PAINT SKYBLUE (-8150 5300);
FORCEPROP 2 LAST CDS_LIB pure_quanta_power
J 0
(-8150 5250);
DISPLAY INVISIBLE (-8150 5250);
FORCEPROP 1 LAST PATH I13
J 0
(-8100 5275);
DISPLAY 0.872340 (-8100 5275);
PAINT AQUA (-8100 5275);
DISPLAY INVISIBLE (-8100 5275);
FORCEADD Q_CAP..1
(-7200 4150);
FORCEPROP 1 LAST LOCATION C433
J 0
(-7150 4250);
DISPLAY 0.638298 (-7150 4250);
PAINT WHITE (-7150 4250);
FORCEPROP 0 LAST $SEC 1
J 0
(-7150 4275);
DISPLAY 0.680851 (-7150 4275);
PAINT MONO (-7150 4275);
DISPLAY INVISIBLE (-7150 4275);
FORCEPROP 0 LAST CDS_SEC 1
J 0
(-7150 4275);
DISPLAY 0.680851 (-7150 4275);
DISPLAY INVISIBLE (-7150 4275);
FORCEPROP 1 LASTPIN (-7200 4250) $PN 1
J 0
(-7190 4230);
DISPLAY 0.787234 (-7190 4230);
PAINT MONO (-7190 4230);
FORCEPROP 1 LASTPIN (-7200 4050) $PN 2
J 0
(-7190 4030);
DISPLAY 0.787234 (-7190 4030);
PAINT MONO (-7190 4030);
FORCEPROP 1 LAST TOLERANCE 20%
J 0
(-7150 4100);
DISPLAY 0.510638 (-7150 4100);
FORCEPROP 1 LAST MATERIAL X6S
J 0
(-7150 4050);
DISPLAY 0.510638 (-7150 4050);
FORCEPROP 1 LAST PACK_TYPE C0805
J 0
(-7150 4000);
DISPLAY 0.510638 (-7150 4000);
FORCEPROP 1 LAST VALUE 100UF
J 0
(-7150 4200);
DISPLAY 0.510638 (-7150 4200);
FORCEPROP 1 LAST VOLTAGE 4V
J 0
(-7150 4150);
DISPLAY 0.510638 (-7150 4150);
FORCEPROP 2 LAST CDS_LIB pure_quanta
J 0
(-7200 4150);
DISPLAY INVISIBLE (-7200 4150);
FORCEPROP 1 LAST PATH I14
J 0
(-7150 4300);
DISPLAY 0.978723 (-7150 4300);
PAINT WHITE (-7150 4300);
DISPLAY INVISIBLE (-7150 4300);
FORCEPROP 1 LAST PART_NUMBER CH710KMEA01
J 0
(-7150 4000);
DISPLAY 0.404255 (-7150 4000);
DISPLAY INVISIBLE (-7150 4000);
FORCEADD Q_CAP..1
(-6975 4150);
FORCEPROP 1 LAST LOCATION C435
J 0
(-6925 4250);
DISPLAY 0.638298 (-6925 4250);
PAINT WHITE (-6925 4250);
FORCEPROP 0 LAST $SEC 1
J 0
(-6925 4275);
DISPLAY 0.680851 (-6925 4275);
PAINT MONO (-6925 4275);
DISPLAY INVISIBLE (-6925 4275);
FORCEPROP 0 LAST CDS_SEC 1
J 0
(-6925 4275);
DISPLAY 0.680851 (-6925 4275);
DISPLAY INVISIBLE (-6925 4275);
FORCEPROP 1 LASTPIN (-6975 4250) $PN 1
J 0
(-6965 4230);
DISPLAY 0.787234 (-6965 4230);
PAINT MONO (-6965 4230);
FORCEPROP 1 LASTPIN (-6975 4050) $PN 2
J 0
(-6965 4030);
DISPLAY 0.787234 (-6965 4030);
PAINT MONO (-6965 4030);
FORCEPROP 1 LAST PACK_TYPE C0402
J 0
(-6925 4000);
DISPLAY 0.510638 (-6925 4000);
FORCEPROP 1 LAST VALUE 22UF
J 0
(-6925 4200);
DISPLAY 0.510638 (-6925 4200);
FORCEPROP 1 LAST MATERIAL X6S
J 0
(-6925 4050);
DISPLAY 0.510638 (-6925 4050);
FORCEPROP 1 LAST TOLERANCE 20%
J 0
(-6925 4100);
DISPLAY 0.510638 (-6925 4100);
FORCEPROP 1 LAST VOLTAGE 4V
J 0
(-6925 4150);
DISPLAY 0.510638 (-6925 4150);
FORCEPROP 2 LAST CDS_LIB pure_quanta
J 0
(-6975 4150);
DISPLAY INVISIBLE (-6975 4150);
FORCEPROP 1 LAST PATH I15
J 0
(-6925 4300);
DISPLAY 0.978723 (-6925 4300);
PAINT WHITE (-6925 4300);
DISPLAY INVISIBLE (-6925 4300);
FORCEPROP 1 LAST PART_NUMBER CH622KMEB02
J 0
(-6925 4000);
DISPLAY 0.978723 (-6925 4000);
DISPLAY INVISIBLE (-6925 4000);
FORCEADD Q_CAP..1
(-6775 4150);
FORCEPROP 1 LAST LOCATION C437
J 0
(-6725 4250);
DISPLAY 0.808511 (-6725 4250);
PAINT WHITE (-6725 4250);
FORCEPROP 0 LAST $SEC 1
J 0
(-6725 4300);
DISPLAY 0.680851 (-6725 4300);
PAINT MONO (-6725 4300);
DISPLAY INVISIBLE (-6725 4300);
FORCEPROP 0 LAST CDS_SEC 1
J 0
(-6725 4300);
DISPLAY 0.680851 (-6725 4300);
DISPLAY INVISIBLE (-6725 4300);
FORCEPROP 1 LASTPIN (-6775 4250) $PN 1
J 0
(-6765 4230);
DISPLAY 0.787234 (-6765 4230);
PAINT MONO (-6765 4230);
FORCEPROP 1 LASTPIN (-6775 4050) $PN 2
J 0
(-6765 4030);
DISPLAY 0.787234 (-6765 4030);
PAINT MONO (-6765 4030);
FORCEPROP 1 LAST VALUE 10UF
J 0
(-6725 4200);
DISPLAY 0.510638 (-6725 4200);
FORCEPROP 1 LAST VOLTAGE 6.3V
J 0
(-6725 4150);
DISPLAY 0.510638 (-6725 4150);
FORCEPROP 1 LAST TOLERANCE 20%
J 0
(-6725 4100);
DISPLAY 0.510638 (-6725 4100);
FORCEPROP 1 LAST PACK_TYPE C0402
J 0
(-6725 4000);
DISPLAY 0.510638 (-6725 4000);
FORCEPROP 1 LAST MATERIAL X6S
J 0
(-6725 4050);
DISPLAY 0.510638 (-6725 4050);
FORCEPROP 2 LAST CDS_LIB pure_quanta
J 0
(-6775 4150);
DISPLAY INVISIBLE (-6775 4150);
FORCEPROP 1 LAST PATH I16
J 0
(-6725 4300);
DISPLAY 0.978723 (-6725 4300);
PAINT WHITE (-6725 4300);
DISPLAY INVISIBLE (-6725 4300);
FORCEPROP 1 LAST PART_NUMBER CH6101MEB01
J 0
(-6725 4000);
DISPLAY 0.978723 (-6725 4000);
DISPLAY INVISIBLE (-6725 4000);
FORCEADD Q_CAP..1
(-7050 4975);
FORCEPROP 1 LAST LOCATION C432
J 0
(-7000 5075);
DISPLAY 0.638298 (-7000 5075);
PAINT WHITE (-7000 5075);
FORCEPROP 0 LAST $SEC 1
J 0
(-7000 5125);
DISPLAY 0.680851 (-7000 5125);
PAINT MONO (-7000 5125);
DISPLAY INVISIBLE (-7000 5125);
FORCEPROP 0 LAST CDS_SEC 1
J 0
(-7000 5125);
DISPLAY 0.680851 (-7000 5125);
DISPLAY INVISIBLE (-7000 5125);
FORCEPROP 1 LASTPIN (-7050 5075) $PN 1
J 0
(-7040 5055);
DISPLAY 0.787234 (-7040 5055);
PAINT MONO (-7040 5055);
FORCEPROP 1 LASTPIN (-7050 4875) $PN 2
J 0
(-7040 4855);
DISPLAY 0.787234 (-7040 4855);
PAINT MONO (-7040 4855);
FORCEPROP 1 LAST VALUE 100UF
J 0
(-7000 5025);
DISPLAY 0.510638 (-7000 5025);
FORCEPROP 1 LAST PACK_TYPE C0805
J 0
(-7000 4825);
DISPLAY 0.510638 (-7000 4825);
FORCEPROP 1 LAST VOLTAGE 4V
J 0
(-7000 4975);
DISPLAY 0.510638 (-7000 4975);
FORCEPROP 1 LAST TOLERANCE 20%
J 0
(-7000 4925);
DISPLAY 0.510638 (-7000 4925);
FORCEPROP 1 LAST MATERIAL X6S
J 0
(-7000 4875);
DISPLAY 0.510638 (-7000 4875);
FORCEPROP 2 LAST CDS_LIB pure_quanta
J 0
(-7050 4975);
DISPLAY INVISIBLE (-7050 4975);
FORCEPROP 1 LAST PATH I17
J 0
(-7000 5125);
DISPLAY 0.978723 (-7000 5125);
PAINT WHITE (-7000 5125);
DISPLAY INVISIBLE (-7000 5125);
FORCEPROP 1 LAST PART_NUMBER CH710KMEA01
J 0
(-7000 4825);
DISPLAY 0.404255 (-7000 4825);
DISPLAY INVISIBLE (-7000 4825);
FORCEADD Q_CAP..1
(-6800 4975);
FORCEPROP 1 LAST LOCATION C434
J 0
(-6750 5075);
DISPLAY 0.510638 (-6750 5075);
PAINT WHITE (-6750 5075);
FORCEPROP 0 LAST $SEC 1
J 0
(-6750 5100);
DISPLAY 0.680851 (-6750 5100);
PAINT MONO (-6750 5100);
DISPLAY INVISIBLE (-6750 5100);
FORCEPROP 0 LAST CDS_SEC 1
J 0
(-6750 5100);
DISPLAY 0.680851 (-6750 5100);
DISPLAY INVISIBLE (-6750 5100);
FORCEPROP 1 LASTPIN (-6800 5075) $PN 1
J 0
(-6790 5055);
DISPLAY 0.787234 (-6790 5055);
PAINT MONO (-6790 5055);
FORCEPROP 1 LASTPIN (-6800 4875) $PN 2
J 0
(-6790 4855);
DISPLAY 0.787234 (-6790 4855);
PAINT MONO (-6790 4855);
FORCEPROP 1 LAST TOLERANCE 20%
J 0
(-6750 4925);
DISPLAY 0.510638 (-6750 4925);
FORCEPROP 1 LAST VALUE 22UF
J 0
(-6750 5025);
DISPLAY 0.510638 (-6750 5025);
FORCEPROP 1 LAST PACK_TYPE C0402
J 0
(-6750 4825);
DISPLAY 0.510638 (-6750 4825);
FORCEPROP 1 LAST VOLTAGE 4V
J 0
(-6750 4975);
DISPLAY 0.510638 (-6750 4975);
FORCEPROP 1 LAST MATERIAL X6S
J 0
(-6750 4875);
DISPLAY 0.510638 (-6750 4875);
FORCEPROP 2 LAST CDS_LIB pure_quanta
J 0
(-6800 4975);
DISPLAY INVISIBLE (-6800 4975);
FORCEPROP 1 LAST PATH I18
J 0
(-6750 5125);
DISPLAY 0.978723 (-6750 5125);
PAINT WHITE (-6750 5125);
DISPLAY INVISIBLE (-6750 5125);
FORCEPROP 1 LAST PART_NUMBER CH622KMEB02
J 0
(-6750 4825);
DISPLAY 0.978723 (-6750 4825);
DISPLAY INVISIBLE (-6750 4825);
FORCEADD Q_CAP..1
(-6575 4150);
FORCEPROP 1 LAST LOCATION C438
J 0
(-6525 4250);
DISPLAY 0.638298 (-6525 4250);
PAINT WHITE (-6525 4250);
FORCEPROP 0 LAST $SEC 1
J 0
(-6525 4275);
DISPLAY 0.680851 (-6525 4275);
PAINT MONO (-6525 4275);
DISPLAY INVISIBLE (-6525 4275);
FORCEPROP 0 LAST CDS_SEC 1
J 0
(-6525 4275);
DISPLAY 0.680851 (-6525 4275);
DISPLAY INVISIBLE (-6525 4275);
FORCEPROP 1 LASTPIN (-6575 4250) $PN 1
J 0
(-6565 4230);
DISPLAY 0.787234 (-6565 4230);
PAINT MONO (-6565 4230);
FORCEPROP 1 LASTPIN (-6575 4050) $PN 2
J 0
(-6565 4030);
DISPLAY 0.787234 (-6565 4030);
PAINT MONO (-6565 4030);
FORCEPROP 1 LAST VALUE 4.7UF
J 0
(-6525 4200);
DISPLAY 0.510638 (-6525 4200);
FORCEPROP 1 LAST MATERIAL X6S
J 0
(-6525 4050);
DISPLAY 0.510638 (-6525 4050);
FORCEPROP 1 LAST TOLERANCE 20%
J 0
(-6525 4100);
DISPLAY 0.510638 (-6525 4100);
FORCEPROP 1 LAST VOLTAGE 6.3V
J 0
(-6525 4150);
DISPLAY 0.510638 (-6525 4150);
FORCEPROP 1 LAST PACK_TYPE 0402
J 0
(-6525 4000);
DISPLAY 0.510638 (-6525 4000);
FORCEPROP 2 LAST CDS_LIB pure_quanta
J 0
(-6575 4150);
DISPLAY INVISIBLE (-6575 4150);
FORCEPROP 1 LAST PATH I19
J 0
(-6525 4300);
DISPLAY 0.978723 (-6525 4300);
PAINT WHITE (-6525 4300);
DISPLAY INVISIBLE (-6525 4300);
FORCEPROP 1 LAST PART_NUMBER CH5471MEB01
J 0
(-6525 4000);
DISPLAY 0.978723 (-6525 4000);
DISPLAY INVISIBLE (-6525 4000);
FORCEADD Q_RES..1
(-7700 3725);
FORCEPROP 1 LAST LOCATION R893
J 0
(-7975 3750);
DISPLAY 0.808511 (-7975 3750);
FORCEPROP 2 LAST SEC 1
J 0
(-7750 3925);
DISPLAY 0.680851 (-7750 3925);
PAINT MONO (-7750 3925);
DISPLAY INVISIBLE (-7750 3925);
FORCEPROP 1 LASTPIN (-7800 3725) $PN 1
J 0
(-7788 3737);
DISPLAY 0.787234 (-7788 3737);
PAINT MONO (-7788 3737);
FORCEPROP 1 LASTPIN (-7600 3725) $PN 2
J 0
(-7638 3737);
DISPLAY 0.787234 (-7638 3737);
PAINT MONO (-7638 3737);
FORCEPROP 1 LAST WATTAGE 1/16W
J 2
(-7700 3625);
DISPLAY 0.638298 (-7700 3625);
FORCEPROP 1 LAST PACK_TYPE 0402LF
J 0
(-7850 3675);
DISPLAY 0.638298 (-7850 3675);
FORCEPROP 1 LAST MATERIAL EMPTY
J 0
(-7675 3625);
DISPLAY 0.638298 (-7675 3625);
FORCEPROP 1 LAST VALUE 0
J 2
(-7550 3750);
DISPLAY 0.638298 (-7550 3750);
FORCEPROP 1 LAST TOLERANCE 5%
J 0
(-7650 3675);
DISPLAY 0.638298 (-7650 3675);
FORCEPROP 2 LAST SEC_TYPE 0402LF
J 0
(-7750 3925);
DISPLAY 0.680851 (-7750 3925);
DISPLAY INVISIBLE (-7750 3925);
FORCEPROP 2 LAST CDS_LIB pure_quanta
J 0
(-7700 3725);
DISPLAY INVISIBLE (-7700 3725);
FORCEPROP 1 LAST PATH I2
J 0
(-7750 3875);
DISPLAY 0.978723 (-7750 3875);
PAINT WHITE (-7750 3875);
DISPLAY INVISIBLE (-7750 3875);
FORCEPROP 1 LAST PART_NUMBER CS00002JB13
J 0
(-7750 3825);
DISPLAY 0.978723 (-7750 3825);
DISPLAY INVISIBLE (-7750 3825);
FORCEADD Q_CAP..1
(-6350 4150);
FORCEPROP 1 LAST LOCATION C440
J 0
(-6300 4250);
DISPLAY 0.808511 (-6300 4250);
PAINT WHITE (-6300 4250);
FORCEPROP 0 LAST $SEC 1
J 0
(-6300 4300);
DISPLAY 0.680851 (-6300 4300);
PAINT MONO (-6300 4300);
DISPLAY INVISIBLE (-6300 4300);
FORCEPROP 0 LAST CDS_SEC 1
J 0
(-6300 4300);
DISPLAY 0.680851 (-6300 4300);
DISPLAY INVISIBLE (-6300 4300);
FORCEPROP 1 LASTPIN (-6350 4250) $PN 1
J 0
(-6340 4230);
DISPLAY 0.787234 (-6340 4230);
PAINT MONO (-6340 4230);
FORCEPROP 1 LASTPIN (-6350 4050) $PN 2
J 0
(-6340 4030);
DISPLAY 0.787234 (-6340 4030);
PAINT MONO (-6340 4030);
FORCEPROP 1 LAST VALUE 1UF
J 0
(-6300 4200);
DISPLAY 0.510638 (-6300 4200);
FORCEPROP 1 LAST PACK_TYPE 0201
J 0
(-6300 4000);
DISPLAY 0.510638 (-6300 4000);
FORCEPROP 1 LAST MATERIAL X6S
J 0
(-6300 4050);
DISPLAY 0.510638 (-6300 4050);
FORCEPROP 1 LAST VOLTAGE 4V
J 0
(-6300 4150);
DISPLAY 0.510638 (-6300 4150);
FORCEPROP 1 LAST TOLERANCE 20%
J 0
(-6300 4100);
DISPLAY 0.510638 (-6300 4100);
FORCEPROP 2 LAST CDS_LIB pure_quanta
J 0
(-6350 4150);
DISPLAY INVISIBLE (-6350 4150);
FORCEPROP 1 LAST PATH I20
J 0
(-6300 4300);
DISPLAY 0.978723 (-6300 4300);
PAINT WHITE (-6300 4300);
DISPLAY INVISIBLE (-6300 4300);
FORCEPROP 1 LAST PART_NUMBER CH-10KMEE00
J 0
(-6300 4000);
DISPLAY 0.510638 (-6300 4000);
DISPLAY INVISIBLE (-6300 4000);
FORCEADD Q_CAP..1
(-6550 4950);
FORCEPROP 1 LAST LOCATION C436
J 0
(-6500 5050);
DISPLAY 0.638298 (-6500 5050);
PAINT WHITE (-6500 5050);
FORCEPROP 0 LAST $SEC 1
J 0
(-6500 5100);
DISPLAY 0.680851 (-6500 5100);
PAINT MONO (-6500 5100);
DISPLAY INVISIBLE (-6500 5100);
FORCEPROP 0 LAST CDS_SEC 1
J 0
(-6500 5100);
DISPLAY 0.680851 (-6500 5100);
DISPLAY INVISIBLE (-6500 5100);
FORCEPROP 1 LASTPIN (-6550 5050) $PN 1
J 0
(-6540 5030);
DISPLAY 0.787234 (-6540 5030);
PAINT MONO (-6540 5030);
FORCEPROP 1 LASTPIN (-6550 4850) $PN 2
J 0
(-6540 4830);
DISPLAY 0.787234 (-6540 4830);
PAINT MONO (-6540 4830);
FORCEPROP 1 LAST PACK_TYPE C0402
J 0
(-6500 4800);
DISPLAY 0.510638 (-6500 4800);
FORCEPROP 1 LAST VALUE 10UF
J 0
(-6500 5000);
DISPLAY 0.510638 (-6500 5000);
FORCEPROP 1 LAST VOLTAGE 6.3V
J 0
(-6500 4950);
DISPLAY 0.510638 (-6500 4950);
FORCEPROP 1 LAST MATERIAL X6S
J 0
(-6500 4850);
DISPLAY 0.510638 (-6500 4850);
FORCEPROP 1 LAST TOLERANCE 20%
J 0
(-6500 4900);
DISPLAY 0.510638 (-6500 4900);
FORCEPROP 2 LAST CDS_LIB pure_quanta
J 0
(-6550 4950);
DISPLAY INVISIBLE (-6550 4950);
FORCEPROP 1 LAST PATH I21
J 0
(-6500 5100);
DISPLAY 0.978723 (-6500 5100);
PAINT WHITE (-6500 5100);
DISPLAY INVISIBLE (-6500 5100);
FORCEPROP 1 LAST PART_NUMBER CH6101MEB01
J 0
(-6500 4800);
DISPLAY 0.978723 (-6500 4800);
DISPLAY INVISIBLE (-6500 4800);
FORCEADD UNIVERSAL_GND..1
(-6375 4675);
FORCEPROP 3 LASTPIN (-6375 4725) SIG_NAME GND\g
J 0
(-6365 4735);
DISPLAY 0.659574 (-6365 4735);
PAINT MONO (-6365 4735);
DISPLAY INVISIBLE (-6365 4735);
FORCEPROP 2 LAST CDS_LIB pure_quanta_power
J 0
(-6375 4675);
DISPLAY INVISIBLE (-6375 4675);
FORCEPROP 1 LAST HDL_POWER GND
J 1
(-6350 4600);
DISPLAY 0.872340 (-6350 4600);
PAINT GREEN (-6350 4600);
DISPLAY INVISIBLE (-6350 4600);
FORCEPROP 1 LAST PATH I22
J 0
(-6300 4675);
DISPLAY 0.872340 (-6300 4675);
PAINT AQUA (-6300 4675);
DISPLAY INVISIBLE (-6300 4675);
FORCEADD Q_CAP..1
(-6300 4950);
FORCEPROP 1 LAST LOCATION C439
J 0
(-6250 5050);
DISPLAY 0.638298 (-6250 5050);
PAINT WHITE (-6250 5050);
FORCEPROP 0 LAST $SEC 1
J 0
(-6250 5100);
DISPLAY 0.680851 (-6250 5100);
PAINT MONO (-6250 5100);
DISPLAY INVISIBLE (-6250 5100);
FORCEPROP 0 LAST CDS_SEC 1
J 0
(-6250 5100);
DISPLAY 0.680851 (-6250 5100);
DISPLAY INVISIBLE (-6250 5100);
FORCEPROP 1 LASTPIN (-6300 5050) $PN 1
J 0
(-6290 5030);
DISPLAY 0.787234 (-6290 5030);
PAINT MONO (-6290 5030);
FORCEPROP 1 LASTPIN (-6300 4850) $PN 2
J 0
(-6290 4830);
DISPLAY 0.787234 (-6290 4830);
PAINT MONO (-6290 4830);
FORCEPROP 1 LAST TOLERANCE 20%
J 0
(-6250 4900);
DISPLAY 0.510638 (-6250 4900);
FORCEPROP 1 LAST VOLTAGE 6.3V
J 0
(-6250 4950);
DISPLAY 0.510638 (-6250 4950);
FORCEPROP 1 LAST MATERIAL X6S
J 0
(-6250 4850);
DISPLAY 0.510638 (-6250 4850);
FORCEPROP 1 LAST PACK_TYPE 0402
J 0
(-6250 4800);
DISPLAY 0.510638 (-6250 4800);
FORCEPROP 1 LAST VALUE 4.7UF
J 0
(-6250 5000);
DISPLAY 0.510638 (-6250 5000);
FORCEPROP 2 LAST CDS_LIB pure_quanta
J 0
(-6300 4950);
DISPLAY INVISIBLE (-6300 4950);
FORCEPROP 1 LAST PATH I23
J 0
(-6250 5100);
DISPLAY 0.978723 (-6250 5100);
PAINT WHITE (-6250 5100);
DISPLAY INVISIBLE (-6250 5100);
FORCEPROP 1 LAST PART_NUMBER CH5471MEB01
J 0
(-6250 4800);
DISPLAY 0.978723 (-6250 4800);
DISPLAY INVISIBLE (-6250 4800);
FORCEADD Q_CAP..1
(-6150 4150);
FORCEPROP 1 LAST LOCATION C442
J 0
(-6100 4250);
DISPLAY 0.808511 (-6100 4250);
PAINT WHITE (-6100 4250);
FORCEPROP 0 LAST $SEC 1
J 0
(-6100 4300);
DISPLAY 0.680851 (-6100 4300);
PAINT MONO (-6100 4300);
DISPLAY INVISIBLE (-6100 4300);
FORCEPROP 0 LAST CDS_SEC 1
J 0
(-6100 4300);
DISPLAY 0.680851 (-6100 4300);
DISPLAY INVISIBLE (-6100 4300);
FORCEPROP 1 LASTPIN (-6150 4250) $PN 1
J 0
(-6140 4230);
DISPLAY 0.787234 (-6140 4230);
PAINT MONO (-6140 4230);
FORCEPROP 1 LASTPIN (-6150 4050) $PN 2
J 0
(-6140 4030);
DISPLAY 0.787234 (-6140 4030);
PAINT MONO (-6140 4030);
FORCEPROP 1 LAST TOLERANCE 20%
J 0
(-6100 4100);
DISPLAY 0.510638 (-6100 4100);
FORCEPROP 1 LAST VALUE 1UF
J 0
(-6100 4200);
DISPLAY 0.510638 (-6100 4200);
FORCEPROP 1 LAST VOLTAGE 4V
J 0
(-6100 4150);
DISPLAY 0.510638 (-6100 4150);
FORCEPROP 1 LAST MATERIAL X6S
J 0
(-6100 4050);
DISPLAY 0.510638 (-6100 4050);
FORCEPROP 1 LAST PACK_TYPE 0201
J 0
(-6100 4000);
DISPLAY 0.510638 (-6100 4000);
FORCEPROP 2 LAST CDS_LIB pure_quanta
J 0
(-6150 4150);
DISPLAY INVISIBLE (-6150 4150);
FORCEPROP 1 LAST PATH I24
J 0
(-6100 4300);
DISPLAY 0.978723 (-6100 4300);
PAINT WHITE (-6100 4300);
DISPLAY INVISIBLE (-6100 4300);
FORCEPROP 1 LAST PART_NUMBER CH-10KMEE00
J 0
(-6100 4000);
DISPLAY 0.510638 (-6100 4000);
DISPLAY INVISIBLE (-6100 4000);
FORCEADD Q_CAP..1
(-5925 4150);
FORCEPROP 1 LAST LOCATION C443
J 0
(-5875 4250);
DISPLAY 0.978723 (-5875 4250);
PAINT WHITE (-5875 4250);
FORCEPROP 0 LAST $SEC 1
J 0
(-5875 4300);
DISPLAY 0.680851 (-5875 4300);
PAINT MONO (-5875 4300);
DISPLAY INVISIBLE (-5875 4300);
FORCEPROP 0 LAST CDS_SEC 1
J 0
(-5875 4300);
DISPLAY 0.680851 (-5875 4300);
DISPLAY INVISIBLE (-5875 4300);
FORCEPROP 1 LASTPIN (-5925 4250) $PN 1
J 0
(-5915 4230);
DISPLAY 0.787234 (-5915 4230);
PAINT MONO (-5915 4230);
FORCEPROP 1 LASTPIN (-5925 4050) $PN 2
J 0
(-5915 4030);
DISPLAY 0.787234 (-5915 4030);
PAINT MONO (-5915 4030);
FORCEPROP 1 LAST VALUE 0.1UF
J 0
(-5875 4200);
DISPLAY 0.638298 (-5875 4200);
FORCEPROP 1 LAST VOLTAGE 10V
J 0
(-5875 4150);
DISPLAY 0.638298 (-5875 4150);
FORCEPROP 1 LAST MATERIAL X7S
J 0
(-5875 4050);
DISPLAY 0.638298 (-5875 4050);
FORCEPROP 1 LAST TOLERANCE 10%
J 0
(-5875 4100);
DISPLAY 0.638298 (-5875 4100);
FORCEPROP 1 LAST PACK_TYPE C0201
J 0
(-5875 4000);
DISPLAY 0.638298 (-5875 4000);
FORCEPROP 2 LAST CDS_LIB pure_quanta
J 0
(-5925 4150);
DISPLAY INVISIBLE (-5925 4150);
FORCEPROP 1 LAST PATH I25
J 0
(-5875 4300);
DISPLAY 0.978723 (-5875 4300);
PAINT WHITE (-5875 4300);
DISPLAY INVISIBLE (-5875 4300);
FORCEPROP 1 LAST PART_NUMBER CH4102K6E00
J 0
(-5875 4000);
DISPLAY 0.978723 (-5875 4000);
DISPLAY INVISIBLE (-5875 4000);
FORCEADD Q_CAP..1
(-5675 4150);
FORCEPROP 1 LAST LOCATION C445
J 0
(-5625 4250);
DISPLAY 0.978723 (-5625 4250);
PAINT WHITE (-5625 4250);
FORCEPROP 0 LAST $SEC 1
J 0
(-5625 4300);
DISPLAY 0.680851 (-5625 4300);
PAINT MONO (-5625 4300);
DISPLAY INVISIBLE (-5625 4300);
FORCEPROP 0 LAST CDS_SEC 1
J 0
(-5625 4300);
DISPLAY 0.680851 (-5625 4300);
DISPLAY INVISIBLE (-5625 4300);
FORCEPROP 1 LASTPIN (-5675 4250) $PN 1
J 0
(-5665 4230);
DISPLAY 0.787234 (-5665 4230);
PAINT MONO (-5665 4230);
FORCEPROP 1 LASTPIN (-5675 4050) $PN 2
J 0
(-5665 4030);
DISPLAY 0.787234 (-5665 4030);
PAINT MONO (-5665 4030);
FORCEPROP 1 LAST PACK_TYPE C0201
J 0
(-5625 4000);
DISPLAY 0.638298 (-5625 4000);
FORCEPROP 1 LAST VALUE 0.1UF
J 0
(-5625 4200);
DISPLAY 0.638298 (-5625 4200);
FORCEPROP 1 LAST MATERIAL X7S
J 0
(-5625 4050);
DISPLAY 0.638298 (-5625 4050);
FORCEPROP 1 LAST VOLTAGE 10V
J 0
(-5625 4150);
DISPLAY 0.638298 (-5625 4150);
FORCEPROP 1 LAST TOLERANCE 10%
J 0
(-5625 4100);
DISPLAY 0.638298 (-5625 4100);
FORCEPROP 2 LAST CDS_LIB pure_quanta
J 0
(-5675 4150);
DISPLAY INVISIBLE (-5675 4150);
FORCEPROP 1 LAST PATH I26
J 0
(-5625 4300);
DISPLAY 0.978723 (-5625 4300);
PAINT WHITE (-5625 4300);
DISPLAY INVISIBLE (-5625 4300);
FORCEPROP 1 LAST PART_NUMBER CH4102K6E00
J 0
(-5625 4000);
DISPLAY 0.978723 (-5625 4000);
DISPLAY INVISIBLE (-5625 4000);
FORCEADD Q_CAP..1
(-5425 4150);
FORCEPROP 1 LAST LOCATION C446
J 0
(-5375 4250);
DISPLAY 0.978723 (-5375 4250);
PAINT WHITE (-5375 4250);
FORCEPROP 0 LAST $SEC 1
J 0
(-5375 4300);
DISPLAY 0.680851 (-5375 4300);
PAINT MONO (-5375 4300);
DISPLAY INVISIBLE (-5375 4300);
FORCEPROP 0 LAST CDS_SEC 1
J 0
(-5375 4300);
DISPLAY 0.680851 (-5375 4300);
DISPLAY INVISIBLE (-5375 4300);
FORCEPROP 1 LASTPIN (-5425 4250) $PN 1
J 0
(-5415 4230);
DISPLAY 0.787234 (-5415 4230);
PAINT MONO (-5415 4230);
FORCEPROP 1 LASTPIN (-5425 4050) $PN 2
J 0
(-5415 4030);
DISPLAY 0.787234 (-5415 4030);
PAINT MONO (-5415 4030);
FORCEPROP 1 LAST PACK_TYPE C0201
J 0
(-5375 4000);
DISPLAY 0.638298 (-5375 4000);
FORCEPROP 1 LAST MATERIAL X7S
J 0
(-5375 4050);
DISPLAY 0.638298 (-5375 4050);
FORCEPROP 1 LAST VOLTAGE 10V
J 0
(-5375 4150);
DISPLAY 0.638298 (-5375 4150);
FORCEPROP 1 LAST VALUE 0.1UF
J 0
(-5375 4200);
DISPLAY 0.638298 (-5375 4200);
FORCEPROP 1 LAST TOLERANCE 10%
J 0
(-5375 4100);
DISPLAY 0.638298 (-5375 4100);
FORCEPROP 2 LAST CDS_LIB pure_quanta
J 0
(-5425 4150);
DISPLAY INVISIBLE (-5425 4150);
FORCEPROP 1 LAST PATH I27
J 0
(-5375 4300);
DISPLAY 0.978723 (-5375 4300);
PAINT WHITE (-5375 4300);
DISPLAY INVISIBLE (-5375 4300);
FORCEPROP 1 LAST PART_NUMBER CH4102K6E00
J 0
(-5375 4000);
DISPLAY 0.978723 (-5375 4000);
DISPLAY INVISIBLE (-5375 4000);
FORCEADD Q_CAP..1
(-5150 4150);
FORCEPROP 1 LAST LOCATION C447
J 0
(-5100 4250);
DISPLAY 0.978723 (-5100 4250);
PAINT WHITE (-5100 4250);
FORCEPROP 0 LAST $SEC 1
J 0
(-5100 4300);
DISPLAY 0.680851 (-5100 4300);
PAINT MONO (-5100 4300);
DISPLAY INVISIBLE (-5100 4300);
FORCEPROP 0 LAST CDS_SEC 1
J 0
(-5100 4300);
DISPLAY 0.680851 (-5100 4300);
DISPLAY INVISIBLE (-5100 4300);
FORCEPROP 1 LASTPIN (-5150 4250) $PN 1
J 0
(-5140 4230);
DISPLAY 0.787234 (-5140 4230);
PAINT MONO (-5140 4230);
FORCEPROP 1 LASTPIN (-5150 4050) $PN 2
J 0
(-5140 4030);
DISPLAY 0.787234 (-5140 4030);
PAINT MONO (-5140 4030);
FORCEPROP 1 LAST PACK_TYPE C0201
J 0
(-5100 4000);
DISPLAY 0.638298 (-5100 4000);
FORCEPROP 1 LAST TOLERANCE 10%
J 0
(-5100 4100);
DISPLAY 0.638298 (-5100 4100);
FORCEPROP 1 LAST MATERIAL X7S
J 0
(-5100 4050);
DISPLAY 0.638298 (-5100 4050);
FORCEPROP 1 LAST VOLTAGE 10V
J 0
(-5100 4150);
DISPLAY 0.638298 (-5100 4150);
FORCEPROP 1 LAST VALUE 0.1UF
J 0
(-5100 4200);
DISPLAY 0.638298 (-5100 4200);
FORCEPROP 2 LAST CDS_LIB pure_quanta
J 0
(-5150 4150);
DISPLAY INVISIBLE (-5150 4150);
FORCEPROP 1 LAST PATH I28
J 0
(-5100 4300);
DISPLAY 0.978723 (-5100 4300);
PAINT WHITE (-5100 4300);
DISPLAY INVISIBLE (-5100 4300);
FORCEPROP 1 LAST PART_NUMBER CH4102K6E00
J 0
(-5100 4000);
DISPLAY 0.978723 (-5100 4000);
DISPLAY INVISIBLE (-5100 4000);
FORCEADD VCC_CORE..1
(-4300 5925);
FORCEPROP 3 LASTPIN (-4300 5875) SIG_NAME P0V9_CPU1_RT_2D\g
J 0
(-4290 5885);
DISPLAY 0.659574 (-4290 5885);
PAINT MONO (-4290 5885);
DISPLAY INVISIBLE (-4290 5885);
FORCEPROP 1 LAST HDL_POWER P0V9_CPU1_RT_2D
J 1
(-4300 5975);
DISPLAY 0.617021 (-4300 5975);
PAINT GREEN (-4300 5975);
FORCEPROP 2 LAST CDS_LIB pure_quanta_power
J 0
(-4300 5925);
DISPLAY INVISIBLE (-4300 5925);
FORCEPROP 1 LAST PATH I29
J 0
(-4250 5950);
DISPLAY 0.872340 (-4250 5950);
PAINT AQUA (-4250 5950);
DISPLAY INVISIBLE (-4250 5950);
FORCEADD UNIVERSAL_GND..1
(-6500 2650);
FORCEPROP 3 LASTPIN (-6500 2700) SIG_NAME GND\g
J 0
(-6490 2710);
DISPLAY 0.659574 (-6490 2710);
PAINT MONO (-6490 2710);
DISPLAY INVISIBLE (-6490 2710);
FORCEPROP 2 LAST CDS_LIB pure_quanta_power
J 0
(-6500 2650);
DISPLAY INVISIBLE (-6500 2650);
FORCEPROP 1 LAST HDL_POWER GND
J 1
(-6475 2575);
DISPLAY 0.872340 (-6475 2575);
PAINT GREEN (-6475 2575);
DISPLAY INVISIBLE (-6475 2575);
FORCEPROP 1 LAST PATH I3
J 0
(-6425 2650);
DISPLAY 0.872340 (-6425 2650);
PAINT AQUA (-6425 2650);
DISPLAY INVISIBLE (-6425 2650);
FORCEADD VCC_CORE..1
(-3150 1625);
FORCEPROP 3 LASTPIN (-3150 1575) SIG_NAME P0V9_CPU1_RT3_2A_2D\g
J 0
(-3140 1585);
DISPLAY 0.659574 (-3140 1585);
PAINT MONO (-3140 1585);
DISPLAY INVISIBLE (-3140 1585);
FORCEPROP 1 LAST HDL_POWER P0V9_CPU1_RT3_2A_2D
J 1
(-3150 1675);
DISPLAY 0.617021 (-3150 1675);
PAINT GREEN (-3150 1675);
FORCEPROP 2 LAST CDS_LIB pure_quanta_power
J 0
(-3150 1625);
DISPLAY INVISIBLE (-3150 1625);
FORCEPROP 1 LAST PATH I30
J 0
(-3100 1650);
DISPLAY 0.872340 (-3100 1650);
PAINT AQUA (-3100 1650);
DISPLAY INVISIBLE (-3100 1650);
FORCEADD UNIVERSAL_GND..1
(-2325 775);
FORCEPROP 3 LASTPIN (-2325 825) SIG_NAME GND\g
J 0
(-2315 835);
DISPLAY 0.659574 (-2315 835);
PAINT MONO (-2315 835);
DISPLAY INVISIBLE (-2315 835);
FORCEPROP 2 LAST CDS_LIB pure_quanta_power
J 0
(-2325 775);
DISPLAY INVISIBLE (-2325 775);
FORCEPROP 1 LAST HDL_POWER GND
J 1
(-2300 700);
DISPLAY 0.872340 (-2300 700);
PAINT GREEN (-2300 700);
DISPLAY INVISIBLE (-2300 700);
FORCEPROP 1 LAST PATH I31
J 0
(-2250 775);
DISPLAY 0.872340 (-2250 775);
PAINT AQUA (-2250 775);
DISPLAY INVISIBLE (-2250 775);
FORCEADD Q_CAP..1
(-2475 1100);
FORCEPROP 1 LAST LOCATION C463
J 0
(-2425 1200);
DISPLAY 0.978723 (-2425 1200);
PAINT WHITE (-2425 1200);
FORCEPROP 0 LAST $SEC 1
J 0
(-2425 1250);
DISPLAY 0.680851 (-2425 1250);
PAINT MONO (-2425 1250);
DISPLAY INVISIBLE (-2425 1250);
FORCEPROP 0 LAST CDS_SEC 1
J 0
(-2425 1250);
DISPLAY 0.680851 (-2425 1250);
DISPLAY INVISIBLE (-2425 1250);
FORCEPROP 1 LASTPIN (-2475 1200) $PN 1
J 0
(-2465 1180);
DISPLAY 0.787234 (-2465 1180);
PAINT MONO (-2465 1180);
FORCEPROP 1 LASTPIN (-2475 1000) $PN 2
J 0
(-2465 980);
DISPLAY 0.787234 (-2465 980);
PAINT MONO (-2465 980);
FORCEPROP 1 LAST VALUE 0.1UF
J 0
(-2425 1150);
DISPLAY 0.638298 (-2425 1150);
FORCEPROP 1 LAST VOLTAGE 10V
J 0
(-2425 1100);
DISPLAY 0.638298 (-2425 1100);
FORCEPROP 1 LAST TOLERANCE 10%
J 0
(-2425 1050);
DISPLAY 0.638298 (-2425 1050);
FORCEPROP 1 LAST MATERIAL X7S
J 0
(-2425 1000);
DISPLAY 0.638298 (-2425 1000);
FORCEPROP 1 LAST PACK_TYPE C0201
J 0
(-2425 950);
DISPLAY 0.638298 (-2425 950);
FORCEPROP 2 LAST CDS_LIB pure_quanta
J 0
(-2475 1100);
DISPLAY INVISIBLE (-2475 1100);
FORCEPROP 1 LAST PATH I34
J 0
(-2425 1250);
DISPLAY 0.978723 (-2425 1250);
PAINT WHITE (-2425 1250);
DISPLAY INVISIBLE (-2425 1250);
FORCEPROP 1 LAST PART_NUMBER CH4102K6E00
J 0
(-2425 950);
DISPLAY 0.978723 (-2425 950);
DISPLAY INVISIBLE (-2425 950);
FORCEADD Q_CAP..1
(-2225 1100);
FORCEPROP 1 LAST LOCATION C464
J 0
(-2175 1200);
DISPLAY 0.978723 (-2175 1200);
PAINT WHITE (-2175 1200);
FORCEPROP 0 LAST $SEC 1
J 0
(-2175 1250);
DISPLAY 0.680851 (-2175 1250);
PAINT MONO (-2175 1250);
DISPLAY INVISIBLE (-2175 1250);
FORCEPROP 0 LAST CDS_SEC 1
J 0
(-2175 1250);
DISPLAY 0.680851 (-2175 1250);
DISPLAY INVISIBLE (-2175 1250);
FORCEPROP 1 LASTPIN (-2225 1200) $PN 1
J 0
(-2215 1180);
DISPLAY 0.787234 (-2215 1180);
PAINT MONO (-2215 1180);
FORCEPROP 1 LASTPIN (-2225 1000) $PN 2
J 0
(-2215 980);
DISPLAY 0.787234 (-2215 980);
PAINT MONO (-2215 980);
FORCEPROP 1 LAST VOLTAGE 10V
J 0
(-2175 1100);
DISPLAY 0.638298 (-2175 1100);
FORCEPROP 1 LAST TOLERANCE 10%
J 0
(-2175 1050);
DISPLAY 0.638298 (-2175 1050);
FORCEPROP 1 LAST VALUE 0.1UF
J 0
(-2175 1150);
DISPLAY 0.638298 (-2175 1150);
FORCEPROP 1 LAST PACK_TYPE C0201
J 0
(-2175 950);
DISPLAY 0.638298 (-2175 950);
FORCEPROP 1 LAST MATERIAL X7S
J 0
(-2175 1000);
DISPLAY 0.638298 (-2175 1000);
FORCEPROP 2 LAST CDS_LIB pure_quanta
J 0
(-2225 1100);
DISPLAY INVISIBLE (-2225 1100);
FORCEPROP 1 LAST PATH I35
J 0
(-2175 1250);
DISPLAY 0.978723 (-2175 1250);
PAINT WHITE (-2175 1250);
DISPLAY INVISIBLE (-2175 1250);
FORCEPROP 1 LAST PART_NUMBER CH4102K6E00
J 0
(-2175 950);
DISPLAY 0.978723 (-2175 950);
DISPLAY INVISIBLE (-2175 950);
FORCEADD Q_RES..1
(-3925 2450);
FORCEPROP 1 LAST LOCATION R900
J 0
(-3975 2500);
DISPLAY 0.978723 (-3975 2500);
FORCEPROP 0 LAST $SEC 1
J 0
(-3975 2550);
DISPLAY 0.680851 (-3975 2550);
PAINT MONO (-3975 2550);
DISPLAY INVISIBLE (-3975 2550);
FORCEPROP 0 LAST CDS_SEC 1
J 0
(-3975 2550);
DISPLAY 0.680851 (-3975 2550);
DISPLAY INVISIBLE (-3975 2550);
FORCEPROP 1 LASTPIN (-4025 2450) $PN 1
J 0
(-4013 2462);
DISPLAY 0.787234 (-4013 2462);
PAINT MONO (-4013 2462);
FORCEPROP 1 LASTPIN (-3825 2450) $PN 2
J 0
(-3863 2462);
DISPLAY 0.787234 (-3863 2462);
PAINT MONO (-3863 2462);
FORCEPROP 1 LAST PACK_TYPE 0603LF
J 0
(-3675 2300);
DISPLAY 0.978723 (-3675 2300);
FORCEPROP 1 LAST WATTAGE 1/4W
J 2
(-3950 2300);
DISPLAY 0.978723 (-3950 2300);
FORCEPROP 1 LAST MATERIAL CHIP
J 0
(-3925 2300);
DISPLAY 0.978723 (-3925 2300);
FORCEPROP 1 LAST TOLERANCE 5%
J 0
(-3925 2350);
DISPLAY 0.978723 (-3925 2350);
FORCEPROP 1 LAST VALUE 0
J 2
(-3950 2350);
DISPLAY 0.978723 (-3950 2350);
FORCEPROP 2 LAST CDS_LIB pure_quanta
J 0
(-3925 2450);
DISPLAY INVISIBLE (-3925 2450);
FORCEPROP 1 LAST PATH I36
J 0
(-3975 2600);
DISPLAY 0.978723 (-3975 2600);
PAINT WHITE (-3975 2600);
DISPLAY INVISIBLE (-3975 2600);
FORCEPROP 1 LAST PART_NUMBER CS00006J900
J 0
(-4150 2225);
DISPLAY 0.978723 (-4150 2225);
DISPLAY INVISIBLE (-4150 2225);
FORCEADD Q_CAP..1
(-3200 2200);
FORCEPROP 1 LAST LOCATION C495
J 0
(-3150 2300);
DISPLAY 0.978723 (-3150 2300);
PAINT WHITE (-3150 2300);
FORCEPROP 0 LAST $SEC 1
J 0
(-3150 2350);
DISPLAY 0.680851 (-3150 2350);
PAINT MONO (-3150 2350);
DISPLAY INVISIBLE (-3150 2350);
FORCEPROP 0 LAST CDS_SEC 1
J 0
(-3150 2350);
DISPLAY 0.680851 (-3150 2350);
DISPLAY INVISIBLE (-3150 2350);
FORCEPROP 1 LASTPIN (-3200 2300) $PN 1
J 0
(-3190 2280);
DISPLAY 0.787234 (-3190 2280);
PAINT MONO (-3190 2280);
FORCEPROP 1 LASTPIN (-3200 2100) $PN 2
J 0
(-3190 2080);
DISPLAY 0.787234 (-3190 2080);
PAINT MONO (-3190 2080);
FORCEPROP 1 LAST VALUE 0.1UF
J 0
(-3150 2250);
DISPLAY 0.638298 (-3150 2250);
FORCEPROP 1 LAST PACK_TYPE C0201
J 0
(-3150 2050);
DISPLAY 0.638298 (-3150 2050);
FORCEPROP 1 LAST MATERIAL X7S
J 0
(-3150 2100);
DISPLAY 0.638298 (-3150 2100);
FORCEPROP 1 LAST VOLTAGE 10V
J 0
(-3150 2200);
DISPLAY 0.638298 (-3150 2200);
FORCEPROP 1 LAST TOLERANCE 10%
J 0
(-3150 2150);
DISPLAY 0.638298 (-3150 2150);
FORCEPROP 2 LAST CDS_LIB pure_quanta
J 0
(-3200 2200);
DISPLAY INVISIBLE (-3200 2200);
FORCEPROP 1 LAST PATH I37
J 0
(-3150 2350);
DISPLAY 0.978723 (-3150 2350);
PAINT WHITE (-3150 2350);
DISPLAY INVISIBLE (-3150 2350);
FORCEPROP 1 LAST PART_NUMBER CH4102K6E00
J 0
(-3150 2050);
DISPLAY 0.978723 (-3150 2050);
DISPLAY INVISIBLE (-3150 2050);
FORCEADD Q_CAP..1
(-3475 2900);
FORCEPROP 1 LAST LOCATION C470
J 0
(-3425 3000);
DISPLAY 0.978723 (-3425 3000);
PAINT WHITE (-3425 3000);
FORCEPROP 0 LAST $SEC 1
J 0
(-3425 3050);
DISPLAY 0.680851 (-3425 3050);
PAINT MONO (-3425 3050);
DISPLAY INVISIBLE (-3425 3050);
FORCEPROP 0 LAST CDS_SEC 1
J 0
(-3425 3050);
DISPLAY 0.680851 (-3425 3050);
DISPLAY INVISIBLE (-3425 3050);
FORCEPROP 1 LASTPIN (-3475 3000) $PN 1
J 0
(-3465 2980);
DISPLAY 0.787234 (-3465 2980);
PAINT MONO (-3465 2980);
FORCEPROP 1 LASTPIN (-3475 2800) $PN 2
J 0
(-3465 2780);
DISPLAY 0.787234 (-3465 2780);
PAINT MONO (-3465 2780);
FORCEPROP 1 LAST VALUE 1UF
J 0
(-3425 2950);
DISPLAY 0.510638 (-3425 2950);
FORCEPROP 1 LAST PACK_TYPE 0201
J 0
(-3425 2750);
DISPLAY 0.510638 (-3425 2750);
FORCEPROP 1 LAST MATERIAL X6S
J 0
(-3425 2800);
DISPLAY 0.510638 (-3425 2800);
FORCEPROP 1 LAST VOLTAGE 4V
J 0
(-3425 2900);
DISPLAY 0.510638 (-3425 2900);
FORCEPROP 1 LAST TOLERANCE 20%
J 0
(-3425 2850);
DISPLAY 0.510638 (-3425 2850);
FORCEPROP 2 LAST CDS_LIB pure_quanta
J 0
(-3475 2900);
DISPLAY INVISIBLE (-3475 2900);
FORCEPROP 1 LAST PATH I38
J 0
(-3425 3050);
DISPLAY 0.978723 (-3425 3050);
PAINT WHITE (-3425 3050);
DISPLAY INVISIBLE (-3425 3050);
FORCEPROP 1 LAST PART_NUMBER CH-10KMEE00
J 0
(-3425 2750);
DISPLAY 0.510638 (-3425 2750);
DISPLAY INVISIBLE (-3425 2750);
FORCEADD Q_CAP..1
(-3250 2900);
FORCEPROP 1 LAST LOCATION C459
J 0
(-3200 3000);
DISPLAY 0.978723 (-3200 3000);
PAINT WHITE (-3200 3000);
FORCEPROP 0 LAST $SEC 1
J 0
(-3200 3050);
DISPLAY 0.680851 (-3200 3050);
PAINT MONO (-3200 3050);
DISPLAY INVISIBLE (-3200 3050);
FORCEPROP 0 LAST CDS_SEC 1
J 0
(-3200 3050);
DISPLAY 0.680851 (-3200 3050);
DISPLAY INVISIBLE (-3200 3050);
FORCEPROP 1 LASTPIN (-3250 3000) $PN 1
J 0
(-3240 2980);
DISPLAY 0.787234 (-3240 2980);
PAINT MONO (-3240 2980);
FORCEPROP 1 LASTPIN (-3250 2800) $PN 2
J 0
(-3240 2780);
DISPLAY 0.787234 (-3240 2780);
PAINT MONO (-3240 2780);
FORCEPROP 1 LAST VOLTAGE 4V
J 0
(-3200 2900);
DISPLAY 0.510638 (-3200 2900);
FORCEPROP 1 LAST VALUE 1UF
J 0
(-3200 2950);
DISPLAY 0.510638 (-3200 2950);
FORCEPROP 1 LAST PACK_TYPE 0201
J 0
(-3200 2750);
DISPLAY 0.510638 (-3200 2750);
FORCEPROP 1 LAST MATERIAL X6S
J 0
(-3200 2800);
DISPLAY 0.510638 (-3200 2800);
FORCEPROP 1 LAST TOLERANCE 20%
J 0
(-3200 2850);
DISPLAY 0.510638 (-3200 2850);
FORCEPROP 2 LAST CDS_LIB pure_quanta
J 0
(-3250 2900);
DISPLAY INVISIBLE (-3250 2900);
FORCEPROP 1 LAST PATH I39
J 0
(-3200 3050);
DISPLAY 0.978723 (-3200 3050);
PAINT WHITE (-3200 3050);
DISPLAY INVISIBLE (-3200 3050);
FORCEPROP 1 LAST PART_NUMBER CH-10KMEE00
J 0
(-3200 2750);
DISPLAY 0.510638 (-3200 2750);
DISPLAY INVISIBLE (-3200 2750);
FORCEADD Q_CAP..1
(-6775 3075);
FORCEPROP 1 LAST LOCATION C441
J 0
(-6725 3175);
DISPLAY 0.638298 (-6725 3175);
PAINT WHITE (-6725 3175);
FORCEPROP 0 LAST $SEC 1
J 0
(-6725 3225);
DISPLAY 0.680851 (-6725 3225);
PAINT MONO (-6725 3225);
DISPLAY INVISIBLE (-6725 3225);
FORCEPROP 0 LAST CDS_SEC 1
J 0
(-6725 3225);
DISPLAY 0.680851 (-6725 3225);
DISPLAY INVISIBLE (-6725 3225);
FORCEPROP 1 LASTPIN (-6775 3175) $PN 1
J 0
(-6765 3155);
DISPLAY 0.787234 (-6765 3155);
PAINT MONO (-6765 3155);
FORCEPROP 1 LASTPIN (-6775 2975) $PN 2
J 0
(-6765 2955);
DISPLAY 0.787234 (-6765 2955);
PAINT MONO (-6765 2955);
FORCEPROP 1 LAST VALUE 1UF
J 0
(-6725 3125);
DISPLAY 0.510638 (-6725 3125);
FORCEPROP 1 LAST VOLTAGE 4V
J 0
(-6725 3075);
DISPLAY 0.510638 (-6725 3075);
FORCEPROP 1 LAST TOLERANCE 20%
J 0
(-6725 3025);
DISPLAY 0.510638 (-6725 3025);
FORCEPROP 1 LAST MATERIAL X6S
J 0
(-6725 2975);
DISPLAY 0.510638 (-6725 2975);
FORCEPROP 1 LAST PACK_TYPE 0201
J 0
(-6725 2925);
DISPLAY 0.510638 (-6725 2925);
FORCEPROP 2 LAST CDS_LIB pure_quanta
J 0
(-6775 3075);
DISPLAY INVISIBLE (-6775 3075);
FORCEPROP 1 LAST PATH I4
J 0
(-6725 3225);
DISPLAY 0.978723 (-6725 3225);
PAINT WHITE (-6725 3225);
DISPLAY INVISIBLE (-6725 3225);
FORCEPROP 1 LAST PART_NUMBER CH-10KMEE00
J 0
(-6725 2925);
DISPLAY 0.510638 (-6725 2925);
DISPLAY INVISIBLE (-6725 2925);
FORCEADD Q_CAP..1
(-3475 3525);
FORCEPROP 1 LAST LOCATION C480
J 0
(-3425 3625);
DISPLAY 0.978723 (-3425 3625);
PAINT WHITE (-3425 3625);
FORCEPROP 0 LAST $SEC 1
J 0
(-3425 3675);
DISPLAY 0.680851 (-3425 3675);
PAINT MONO (-3425 3675);
DISPLAY INVISIBLE (-3425 3675);
FORCEPROP 0 LAST CDS_SEC 1
J 0
(-3425 3675);
DISPLAY 0.680851 (-3425 3675);
DISPLAY INVISIBLE (-3425 3675);
FORCEPROP 1 LASTPIN (-3475 3625) $PN 1
J 0
(-3465 3605);
DISPLAY 0.787234 (-3465 3605);
PAINT MONO (-3465 3605);
FORCEPROP 1 LASTPIN (-3475 3425) $PN 2
J 0
(-3465 3405);
DISPLAY 0.787234 (-3465 3405);
PAINT MONO (-3465 3405);
FORCEPROP 1 LAST VALUE 10UF
J 0
(-3425 3575);
DISPLAY 0.510638 (-3425 3575);
FORCEPROP 1 LAST VOLTAGE 6.3V
J 0
(-3425 3525);
DISPLAY 0.510638 (-3425 3525);
FORCEPROP 1 LAST MATERIAL X6S
J 0
(-3425 3425);
DISPLAY 0.510638 (-3425 3425);
FORCEPROP 1 LAST TOLERANCE 20%
J 0
(-3425 3475);
DISPLAY 0.510638 (-3425 3475);
FORCEPROP 1 LAST PACK_TYPE C0402
J 0
(-3425 3375);
DISPLAY 0.510638 (-3425 3375);
FORCEPROP 2 LAST CDS_LIB pure_quanta
J 0
(-3475 3525);
DISPLAY INVISIBLE (-3475 3525);
FORCEPROP 1 LAST PATH I40
J 0
(-3425 3675);
DISPLAY 0.978723 (-3425 3675);
PAINT WHITE (-3425 3675);
DISPLAY INVISIBLE (-3425 3675);
FORCEPROP 1 LAST PART_NUMBER CH6101MEB01
J 0
(-3425 3375);
DISPLAY 0.978723 (-3425 3375);
DISPLAY INVISIBLE (-3425 3375);
FORCEADD Q_CAP..1
(-3250 3525);
FORCEPROP 1 LAST LOCATION C490
J 0
(-3200 3625);
DISPLAY 0.978723 (-3200 3625);
PAINT WHITE (-3200 3625);
FORCEPROP 0 LAST $SEC 1
J 0
(-3200 3675);
DISPLAY 0.680851 (-3200 3675);
PAINT MONO (-3200 3675);
DISPLAY INVISIBLE (-3200 3675);
FORCEPROP 0 LAST CDS_SEC 1
J 0
(-3200 3675);
DISPLAY 0.680851 (-3200 3675);
DISPLAY INVISIBLE (-3200 3675);
FORCEPROP 1 LASTPIN (-3250 3625) $PN 1
J 0
(-3240 3605);
DISPLAY 0.787234 (-3240 3605);
PAINT MONO (-3240 3605);
FORCEPROP 1 LASTPIN (-3250 3425) $PN 2
J 0
(-3240 3405);
DISPLAY 0.787234 (-3240 3405);
PAINT MONO (-3240 3405);
FORCEPROP 1 LAST TOLERANCE 20%
J 0
(-3200 3475);
DISPLAY 0.510638 (-3200 3475);
FORCEPROP 1 LAST VOLTAGE 6.3V
J 0
(-3200 3525);
DISPLAY 0.510638 (-3200 3525);
FORCEPROP 1 LAST VALUE 10UF
J 0
(-3200 3575);
DISPLAY 0.510638 (-3200 3575);
FORCEPROP 1 LAST MATERIAL X6S
J 0
(-3200 3425);
DISPLAY 0.510638 (-3200 3425);
FORCEPROP 1 LAST PACK_TYPE C0402
J 0
(-3200 3375);
DISPLAY 0.510638 (-3200 3375);
FORCEPROP 2 LAST CDS_LIB pure_quanta
J 0
(-3250 3525);
DISPLAY INVISIBLE (-3250 3525);
FORCEPROP 1 LAST PATH I41
J 0
(-3200 3675);
DISPLAY 0.978723 (-3200 3675);
PAINT WHITE (-3200 3675);
DISPLAY INVISIBLE (-3200 3675);
FORCEPROP 1 LAST PART_NUMBER CH6101MEB01
J 0
(-3200 3375);
DISPLAY 0.978723 (-3200 3375);
DISPLAY INVISIBLE (-3200 3375);
FORCEADD Q_CAP..1
(-2900 2200);
FORCEPROP 1 LAST LOCATION C500
J 0
(-2850 2300);
DISPLAY 0.978723 (-2850 2300);
PAINT WHITE (-2850 2300);
FORCEPROP 0 LAST $SEC 1
J 0
(-2850 2350);
DISPLAY 0.680851 (-2850 2350);
PAINT MONO (-2850 2350);
DISPLAY INVISIBLE (-2850 2350);
FORCEPROP 0 LAST CDS_SEC 1
J 0
(-2850 2350);
DISPLAY 0.680851 (-2850 2350);
DISPLAY INVISIBLE (-2850 2350);
FORCEPROP 1 LASTPIN (-2900 2300) $PN 1
J 0
(-2890 2280);
DISPLAY 0.787234 (-2890 2280);
PAINT MONO (-2890 2280);
FORCEPROP 1 LASTPIN (-2900 2100) $PN 2
J 0
(-2890 2080);
DISPLAY 0.787234 (-2890 2080);
PAINT MONO (-2890 2080);
FORCEPROP 1 LAST VALUE 0.1UF
J 0
(-2850 2250);
DISPLAY 0.638298 (-2850 2250);
FORCEPROP 1 LAST VOLTAGE 10V
J 0
(-2850 2200);
DISPLAY 0.638298 (-2850 2200);
FORCEPROP 1 LAST PACK_TYPE C0201
J 0
(-2850 2050);
DISPLAY 0.638298 (-2850 2050);
FORCEPROP 1 LAST MATERIAL X7S
J 0
(-2850 2100);
DISPLAY 0.638298 (-2850 2100);
FORCEPROP 1 LAST TOLERANCE 10%
J 0
(-2850 2150);
DISPLAY 0.638298 (-2850 2150);
FORCEPROP 2 LAST CDS_LIB pure_quanta
J 0
(-2900 2200);
DISPLAY INVISIBLE (-2900 2200);
FORCEPROP 1 LAST PATH I42
J 0
(-2850 2350);
DISPLAY 0.978723 (-2850 2350);
PAINT WHITE (-2850 2350);
DISPLAY INVISIBLE (-2850 2350);
FORCEPROP 1 LAST PART_NUMBER CH4102K6E00
J 0
(-2850 2050);
DISPLAY 0.978723 (-2850 2050);
DISPLAY INVISIBLE (-2850 2050);
FORCEADD Q_CAP..1
(-2675 2200);
FORCEPROP 1 LAST LOCATION C473
J 0
(-2625 2300);
DISPLAY 0.978723 (-2625 2300);
PAINT WHITE (-2625 2300);
FORCEPROP 0 LAST $SEC 1
J 0
(-2625 2350);
DISPLAY 0.680851 (-2625 2350);
PAINT MONO (-2625 2350);
DISPLAY INVISIBLE (-2625 2350);
FORCEPROP 0 LAST CDS_SEC 1
J 0
(-2625 2350);
DISPLAY 0.680851 (-2625 2350);
DISPLAY INVISIBLE (-2625 2350);
FORCEPROP 1 LASTPIN (-2675 2300) $PN 1
J 0
(-2665 2280);
DISPLAY 0.787234 (-2665 2280);
PAINT MONO (-2665 2280);
FORCEPROP 1 LASTPIN (-2675 2100) $PN 2
J 0
(-2665 2080);
DISPLAY 0.787234 (-2665 2080);
PAINT MONO (-2665 2080);
FORCEPROP 1 LAST VALUE 0.1UF
J 0
(-2625 2250);
DISPLAY 0.638298 (-2625 2250);
FORCEPROP 1 LAST TOLERANCE 10%
J 0
(-2625 2150);
DISPLAY 0.638298 (-2625 2150);
FORCEPROP 1 LAST VOLTAGE 10V
J 0
(-2625 2200);
DISPLAY 0.638298 (-2625 2200);
FORCEPROP 1 LAST PACK_TYPE C0201
J 0
(-2625 2050);
DISPLAY 0.638298 (-2625 2050);
FORCEPROP 1 LAST MATERIAL X7S
J 0
(-2625 2100);
DISPLAY 0.638298 (-2625 2100);
FORCEPROP 2 LAST CDS_LIB pure_quanta
J 0
(-2675 2200);
DISPLAY INVISIBLE (-2675 2200);
FORCEPROP 1 LAST PATH I43
J 0
(-2625 2350);
DISPLAY 0.978723 (-2625 2350);
PAINT WHITE (-2625 2350);
DISPLAY INVISIBLE (-2625 2350);
FORCEPROP 1 LAST PART_NUMBER CH4102K6E00
J 0
(-2625 2050);
DISPLAY 0.978723 (-2625 2050);
DISPLAY INVISIBLE (-2625 2050);
FORCEADD Q_CAP..1
(-3000 2900);
FORCEPROP 1 LAST LOCATION C448
J 0
(-2950 3000);
DISPLAY 0.978723 (-2950 3000);
PAINT WHITE (-2950 3000);
FORCEPROP 0 LAST $SEC 1
J 0
(-2950 3050);
DISPLAY 0.680851 (-2950 3050);
PAINT MONO (-2950 3050);
DISPLAY INVISIBLE (-2950 3050);
FORCEPROP 0 LAST CDS_SEC 1
J 0
(-2950 3050);
DISPLAY 0.680851 (-2950 3050);
DISPLAY INVISIBLE (-2950 3050);
FORCEPROP 1 LASTPIN (-3000 3000) $PN 1
J 0
(-2990 2980);
DISPLAY 0.787234 (-2990 2980);
PAINT MONO (-2990 2980);
FORCEPROP 1 LASTPIN (-3000 2800) $PN 2
J 0
(-2990 2780);
DISPLAY 0.787234 (-2990 2780);
PAINT MONO (-2990 2780);
FORCEPROP 1 LAST VOLTAGE 4V
J 0
(-2950 2900);
DISPLAY 0.510638 (-2950 2900);
FORCEPROP 1 LAST VALUE 1UF
J 0
(-2950 2950);
DISPLAY 0.510638 (-2950 2950);
FORCEPROP 1 LAST TOLERANCE 20%
J 0
(-2950 2850);
DISPLAY 0.510638 (-2950 2850);
FORCEPROP 1 LAST PACK_TYPE 0201
J 0
(-2950 2750);
DISPLAY 0.510638 (-2950 2750);
FORCEPROP 1 LAST MATERIAL X6S
J 0
(-2950 2800);
DISPLAY 0.510638 (-2950 2800);
FORCEPROP 2 LAST CDS_LIB pure_quanta
J 0
(-3000 2900);
DISPLAY INVISIBLE (-3000 2900);
FORCEPROP 1 LAST PATH I44
J 0
(-2950 3050);
DISPLAY 0.978723 (-2950 3050);
PAINT WHITE (-2950 3050);
DISPLAY INVISIBLE (-2950 3050);
FORCEPROP 1 LAST PART_NUMBER CH-10KMEE00
J 0
(-2950 2750);
DISPLAY 0.510638 (-2950 2750);
DISPLAY INVISIBLE (-2950 2750);
FORCEADD Q_CAP..1
(-2775 2900);
FORCEPROP 1 LAST LOCATION C453
J 0
(-2725 3000);
DISPLAY 0.978723 (-2725 3000);
PAINT WHITE (-2725 3000);
FORCEPROP 0 LAST $SEC 1
J 0
(-2725 3050);
DISPLAY 0.680851 (-2725 3050);
PAINT MONO (-2725 3050);
DISPLAY INVISIBLE (-2725 3050);
FORCEPROP 0 LAST CDS_SEC 1
J 0
(-2725 3050);
DISPLAY 0.680851 (-2725 3050);
DISPLAY INVISIBLE (-2725 3050);
FORCEPROP 1 LASTPIN (-2775 3000) $PN 1
J 0
(-2765 2980);
DISPLAY 0.787234 (-2765 2980);
PAINT MONO (-2765 2980);
FORCEPROP 1 LASTPIN (-2775 2800) $PN 2
J 0
(-2765 2780);
DISPLAY 0.787234 (-2765 2780);
PAINT MONO (-2765 2780);
FORCEPROP 1 LAST TOLERANCE 20%
J 0
(-2725 2850);
DISPLAY 0.510638 (-2725 2850);
FORCEPROP 1 LAST VALUE 1UF
J 0
(-2725 2950);
DISPLAY 0.510638 (-2725 2950);
FORCEPROP 1 LAST PACK_TYPE 0201
J 0
(-2725 2750);
DISPLAY 0.510638 (-2725 2750);
FORCEPROP 1 LAST MATERIAL X6S
J 0
(-2725 2800);
DISPLAY 0.510638 (-2725 2800);
FORCEPROP 1 LAST VOLTAGE 4V
J 0
(-2725 2900);
DISPLAY 0.510638 (-2725 2900);
FORCEPROP 2 LAST CDS_LIB pure_quanta
J 0
(-2775 2900);
DISPLAY INVISIBLE (-2775 2900);
FORCEPROP 1 LAST PATH I45
J 0
(-2725 3050);
DISPLAY 0.978723 (-2725 3050);
PAINT WHITE (-2725 3050);
DISPLAY INVISIBLE (-2725 3050);
FORCEPROP 1 LAST PART_NUMBER CH-10KMEE00
J 0
(-2725 2750);
DISPLAY 0.510638 (-2725 2750);
DISPLAY INVISIBLE (-2725 2750);
FORCEADD Q_CAP..1
(-2425 2200);
FORCEPROP 1 LAST LOCATION C477
J 0
(-2375 2300);
DISPLAY 0.978723 (-2375 2300);
PAINT WHITE (-2375 2300);
FORCEPROP 0 LAST $SEC 1
J 0
(-2375 2350);
DISPLAY 0.680851 (-2375 2350);
PAINT MONO (-2375 2350);
DISPLAY INVISIBLE (-2375 2350);
FORCEPROP 0 LAST CDS_SEC 1
J 0
(-2375 2350);
DISPLAY 0.680851 (-2375 2350);
DISPLAY INVISIBLE (-2375 2350);
FORCEPROP 1 LASTPIN (-2425 2300) $PN 1
J 0
(-2415 2280);
DISPLAY 0.787234 (-2415 2280);
PAINT MONO (-2415 2280);
FORCEPROP 1 LASTPIN (-2425 2100) $PN 2
J 0
(-2415 2080);
DISPLAY 0.787234 (-2415 2080);
PAINT MONO (-2415 2080);
FORCEPROP 1 LAST VALUE 0.1UF
J 0
(-2375 2250);
DISPLAY 0.638298 (-2375 2250);
FORCEPROP 1 LAST VOLTAGE 10V
J 0
(-2375 2200);
DISPLAY 0.638298 (-2375 2200);
FORCEPROP 1 LAST TOLERANCE 10%
J 0
(-2375 2150);
DISPLAY 0.638298 (-2375 2150);
FORCEPROP 1 LAST MATERIAL X7S
J 0
(-2375 2100);
DISPLAY 0.638298 (-2375 2100);
FORCEPROP 1 LAST PACK_TYPE C0201
J 0
(-2375 2050);
DISPLAY 0.638298 (-2375 2050);
FORCEPROP 2 LAST CDS_LIB pure_quanta
J 0
(-2425 2200);
DISPLAY INVISIBLE (-2425 2200);
FORCEPROP 1 LAST PATH I46
J 0
(-2375 2350);
DISPLAY 0.978723 (-2375 2350);
PAINT WHITE (-2375 2350);
DISPLAY INVISIBLE (-2375 2350);
FORCEPROP 1 LAST PART_NUMBER CH4102K6E00
J 0
(-2375 2050);
DISPLAY 0.978723 (-2375 2050);
DISPLAY INVISIBLE (-2375 2050);
FORCEADD Q_CAP..1
(-2175 2200);
FORCEPROP 1 LAST LOCATION C450
J 0
(-2125 2300);
DISPLAY 0.978723 (-2125 2300);
PAINT WHITE (-2125 2300);
FORCEPROP 0 LAST $SEC 1
J 0
(-2125 2350);
DISPLAY 0.680851 (-2125 2350);
PAINT MONO (-2125 2350);
DISPLAY INVISIBLE (-2125 2350);
FORCEPROP 0 LAST CDS_SEC 1
J 0
(-2125 2350);
DISPLAY 0.680851 (-2125 2350);
DISPLAY INVISIBLE (-2125 2350);
FORCEPROP 1 LASTPIN (-2175 2300) $PN 1
J 0
(-2165 2280);
DISPLAY 0.787234 (-2165 2280);
PAINT MONO (-2165 2280);
FORCEPROP 1 LASTPIN (-2175 2100) $PN 2
J 0
(-2165 2080);
DISPLAY 0.787234 (-2165 2080);
PAINT MONO (-2165 2080);
FORCEPROP 1 LAST PACK_TYPE C0201
J 0
(-2125 2050);
DISPLAY 0.638298 (-2125 2050);
FORCEPROP 1 LAST VALUE 0.1UF
J 0
(-2125 2250);
DISPLAY 0.638298 (-2125 2250);
FORCEPROP 1 LAST TOLERANCE 10%
J 0
(-2125 2150);
DISPLAY 0.638298 (-2125 2150);
FORCEPROP 1 LAST VOLTAGE 10V
J 0
(-2125 2200);
DISPLAY 0.638298 (-2125 2200);
FORCEPROP 1 LAST MATERIAL X7S
J 0
(-2125 2100);
DISPLAY 0.638298 (-2125 2100);
FORCEPROP 2 LAST CDS_LIB pure_quanta
J 0
(-2175 2200);
DISPLAY INVISIBLE (-2175 2200);
FORCEPROP 1 LAST PATH I47
J 0
(-2125 2350);
DISPLAY 0.978723 (-2125 2350);
PAINT WHITE (-2125 2350);
DISPLAY INVISIBLE (-2125 2350);
FORCEPROP 1 LAST PART_NUMBER CH4102K6E00
J 0
(-2125 2050);
DISPLAY 0.978723 (-2125 2050);
DISPLAY INVISIBLE (-2125 2050);
FORCEADD Q_CAP..1
(-2525 2900);
FORCEPROP 1 LAST LOCATION C485
J 0
(-2475 3000);
DISPLAY 0.978723 (-2475 3000);
PAINT WHITE (-2475 3000);
FORCEPROP 0 LAST $SEC 1
J 0
(-2475 3050);
DISPLAY 0.680851 (-2475 3050);
PAINT MONO (-2475 3050);
DISPLAY INVISIBLE (-2475 3050);
FORCEPROP 0 LAST CDS_SEC 1
J 0
(-2475 3050);
DISPLAY 0.680851 (-2475 3050);
DISPLAY INVISIBLE (-2475 3050);
FORCEPROP 1 LASTPIN (-2525 3000) $PN 1
J 0
(-2515 2980);
DISPLAY 0.787234 (-2515 2980);
PAINT MONO (-2515 2980);
FORCEPROP 1 LASTPIN (-2525 2800) $PN 2
J 0
(-2515 2780);
DISPLAY 0.787234 (-2515 2780);
PAINT MONO (-2515 2780);
FORCEPROP 1 LAST VALUE 1UF
J 0
(-2475 2950);
DISPLAY 0.510638 (-2475 2950);
FORCEPROP 1 LAST MATERIAL X6S
J 0
(-2475 2800);
DISPLAY 0.510638 (-2475 2800);
FORCEPROP 1 LAST VOLTAGE 4V
J 0
(-2475 2900);
DISPLAY 0.510638 (-2475 2900);
FORCEPROP 1 LAST TOLERANCE 20%
J 0
(-2475 2850);
DISPLAY 0.510638 (-2475 2850);
FORCEPROP 1 LAST PACK_TYPE 0201
J 0
(-2475 2750);
DISPLAY 0.510638 (-2475 2750);
FORCEPROP 2 LAST CDS_LIB pure_quanta
J 0
(-2525 2900);
DISPLAY INVISIBLE (-2525 2900);
FORCEPROP 1 LAST PATH I48
J 0
(-2475 3050);
DISPLAY 0.978723 (-2475 3050);
PAINT WHITE (-2475 3050);
DISPLAY INVISIBLE (-2475 3050);
FORCEPROP 1 LAST PART_NUMBER CH-10KMEE00
J 0
(-2475 2750);
DISPLAY 0.510638 (-2475 2750);
DISPLAY INVISIBLE (-2475 2750);
FORCEADD Q_CAP..1
(-2300 2875);
FORCEPROP 1 LAST LOCATION C488
J 0
(-2250 2975);
DISPLAY 0.978723 (-2250 2975);
PAINT WHITE (-2250 2975);
FORCEPROP 0 LAST $SEC 1
J 0
(-2250 3025);
DISPLAY 0.680851 (-2250 3025);
PAINT MONO (-2250 3025);
DISPLAY INVISIBLE (-2250 3025);
FORCEPROP 0 LAST CDS_SEC 1
J 0
(-2250 3025);
DISPLAY 0.680851 (-2250 3025);
DISPLAY INVISIBLE (-2250 3025);
FORCEPROP 1 LASTPIN (-2300 2975) $PN 1
J 0
(-2290 2955);
DISPLAY 0.787234 (-2290 2955);
PAINT MONO (-2290 2955);
FORCEPROP 1 LASTPIN (-2300 2775) $PN 2
J 0
(-2290 2755);
DISPLAY 0.787234 (-2290 2755);
PAINT MONO (-2290 2755);
FORCEPROP 1 LAST VOLTAGE 4V
J 0
(-2250 2875);
DISPLAY 0.510638 (-2250 2875);
FORCEPROP 1 LAST MATERIAL X6S
J 0
(-2250 2775);
DISPLAY 0.510638 (-2250 2775);
FORCEPROP 1 LAST VALUE 1UF
J 0
(-2250 2925);
DISPLAY 0.510638 (-2250 2925);
FORCEPROP 1 LAST TOLERANCE 20%
J 0
(-2250 2825);
DISPLAY 0.510638 (-2250 2825);
FORCEPROP 1 LAST PACK_TYPE 0201
J 0
(-2250 2725);
DISPLAY 0.510638 (-2250 2725);
FORCEPROP 2 LAST CDS_LIB pure_quanta
J 0
(-2300 2875);
DISPLAY INVISIBLE (-2300 2875);
FORCEPROP 1 LAST PATH I49
J 0
(-2250 3025);
DISPLAY 0.978723 (-2250 3025);
PAINT WHITE (-2250 3025);
DISPLAY INVISIBLE (-2250 3025);
FORCEPROP 1 LAST PART_NUMBER CH-10KMEE00
J 0
(-2250 2725);
DISPLAY 0.510638 (-2250 2725);
DISPLAY INVISIBLE (-2250 2725);
FORCEADD P1V0..1
(-6900 3450);
FORCEPROP 3 LASTPIN (-6900 3400) SIG_NAME P1V8_CPU1_RT3_1A_1D\g
J 0
(-6890 3410);
DISPLAY 0.659574 (-6890 3410);
PAINT MONO (-6890 3410);
DISPLAY INVISIBLE (-6890 3410);
FORCEPROP 1 LAST HDL_POWER P1V8_CPU1_RT3_1A_1D
J 1
(-6900 3500);
DISPLAY 0.489362 (-6900 3500);
PAINT SKYBLUE (-6900 3500);
FORCEPROP 2 LAST CDS_LIB pure_quanta_power
J 0
(-6900 3450);
DISPLAY INVISIBLE (-6900 3450);
FORCEPROP 1 LAST PATH I5
J 0
(-6850 3475);
DISPLAY 0.872340 (-6850 3475);
PAINT AQUA (-6850 3475);
DISPLAY INVISIBLE (-6850 3475);
FORCEADD Q_CAP..1
(-3025 3525);
FORCEPROP 1 LAST LOCATION C472
J 0
(-2975 3625);
DISPLAY 0.978723 (-2975 3625);
PAINT WHITE (-2975 3625);
FORCEPROP 0 LAST $SEC 1
J 0
(-2975 3675);
DISPLAY 0.680851 (-2975 3675);
PAINT MONO (-2975 3675);
DISPLAY INVISIBLE (-2975 3675);
FORCEPROP 0 LAST CDS_SEC 1
J 0
(-2975 3675);
DISPLAY 0.680851 (-2975 3675);
DISPLAY INVISIBLE (-2975 3675);
FORCEPROP 1 LASTPIN (-3025 3625) $PN 1
J 0
(-3015 3605);
DISPLAY 0.787234 (-3015 3605);
PAINT MONO (-3015 3605);
FORCEPROP 1 LASTPIN (-3025 3425) $PN 2
J 0
(-3015 3405);
DISPLAY 0.787234 (-3015 3405);
PAINT MONO (-3015 3405);
FORCEPROP 1 LAST MATERIAL X6S
J 0
(-2975 3425);
DISPLAY 0.510638 (-2975 3425);
FORCEPROP 1 LAST VOLTAGE 6.3V
J 0
(-2975 3525);
DISPLAY 0.510638 (-2975 3525);
FORCEPROP 1 LAST VALUE 4.7UF
J 0
(-2975 3575);
DISPLAY 0.510638 (-2975 3575);
FORCEPROP 1 LAST PACK_TYPE 0402
J 0
(-2975 3375);
DISPLAY 0.510638 (-2975 3375);
FORCEPROP 1 LAST TOLERANCE 20%
J 0
(-2975 3475);
DISPLAY 0.510638 (-2975 3475);
FORCEPROP 2 LAST CDS_LIB pure_quanta
J 0
(-3025 3525);
DISPLAY INVISIBLE (-3025 3525);
FORCEPROP 1 LAST PATH I50
J 0
(-2975 3675);
DISPLAY 0.978723 (-2975 3675);
PAINT WHITE (-2975 3675);
DISPLAY INVISIBLE (-2975 3675);
FORCEPROP 1 LAST PART_NUMBER CH5471MEB01
J 0
(-2975 3375);
DISPLAY 0.978723 (-2975 3375);
DISPLAY INVISIBLE (-2975 3375);
FORCEADD Q_CAP..1
(-2800 3525);
FORCEPROP 1 LAST LOCATION C469
J 0
(-2750 3625);
DISPLAY 0.978723 (-2750 3625);
PAINT WHITE (-2750 3625);
FORCEPROP 0 LAST $SEC 1
J 0
(-2750 3675);
DISPLAY 0.680851 (-2750 3675);
PAINT MONO (-2750 3675);
DISPLAY INVISIBLE (-2750 3675);
FORCEPROP 0 LAST CDS_SEC 1
J 0
(-2750 3675);
DISPLAY 0.680851 (-2750 3675);
DISPLAY INVISIBLE (-2750 3675);
FORCEPROP 1 LASTPIN (-2800 3625) $PN 1
J 0
(-2790 3605);
DISPLAY 0.787234 (-2790 3605);
PAINT MONO (-2790 3605);
FORCEPROP 1 LASTPIN (-2800 3425) $PN 2
J 0
(-2790 3405);
DISPLAY 0.787234 (-2790 3405);
PAINT MONO (-2790 3405);
FORCEPROP 1 LAST PACK_TYPE 0402
J 0
(-2750 3375);
DISPLAY 0.510638 (-2750 3375);
FORCEPROP 1 LAST VOLTAGE 6.3V
J 0
(-2750 3525);
DISPLAY 0.510638 (-2750 3525);
FORCEPROP 1 LAST TOLERANCE 20%
J 0
(-2750 3475);
DISPLAY 0.510638 (-2750 3475);
FORCEPROP 1 LAST VALUE 4.7UF
J 0
(-2750 3575);
DISPLAY 0.510638 (-2750 3575);
FORCEPROP 1 LAST MATERIAL X6S
J 0
(-2750 3425);
DISPLAY 0.510638 (-2750 3425);
FORCEPROP 2 LAST CDS_LIB pure_quanta
J 0
(-2800 3525);
DISPLAY INVISIBLE (-2800 3525);
FORCEPROP 1 LAST PATH I51
J 0
(-2750 3675);
DISPLAY 0.978723 (-2750 3675);
PAINT WHITE (-2750 3675);
DISPLAY INVISIBLE (-2750 3675);
FORCEPROP 1 LAST PART_NUMBER CH5471MEB01
J 0
(-2750 3375);
DISPLAY 0.978723 (-2750 3375);
DISPLAY INVISIBLE (-2750 3375);
FORCEADD Q_CAP..1
(-2325 3525);
FORCEPROP 1 LAST LOCATION C494
J 0
(-2275 3625);
DISPLAY 0.978723 (-2275 3625);
PAINT WHITE (-2275 3625);
FORCEPROP 0 LAST $SEC 1
J 0
(-2275 3675);
DISPLAY 0.680851 (-2275 3675);
PAINT MONO (-2275 3675);
DISPLAY INVISIBLE (-2275 3675);
FORCEPROP 0 LAST CDS_SEC 1
J 0
(-2275 3675);
DISPLAY 0.680851 (-2275 3675);
DISPLAY INVISIBLE (-2275 3675);
FORCEPROP 1 LASTPIN (-2325 3625) $PN 1
J 0
(-2315 3605);
DISPLAY 0.787234 (-2315 3605);
PAINT MONO (-2315 3605);
FORCEPROP 1 LASTPIN (-2325 3425) $PN 2
J 0
(-2315 3405);
DISPLAY 0.787234 (-2315 3405);
PAINT MONO (-2315 3405);
FORCEPROP 1 LAST PACK_TYPE 0402
J 0
(-2275 3375);
DISPLAY 0.510638 (-2275 3375);
FORCEPROP 1 LAST VOLTAGE 6.3V
J 0
(-2275 3525);
DISPLAY 0.510638 (-2275 3525);
FORCEPROP 1 LAST MATERIAL X6S
J 0
(-2275 3425);
DISPLAY 0.510638 (-2275 3425);
FORCEPROP 1 LAST TOLERANCE 20%
J 0
(-2275 3475);
DISPLAY 0.510638 (-2275 3475);
FORCEPROP 1 LAST VALUE 4.7UF
J 0
(-2275 3575);
DISPLAY 0.510638 (-2275 3575);
FORCEPROP 2 LAST CDS_LIB pure_quanta
J 0
(-2325 3525);
DISPLAY INVISIBLE (-2325 3525);
FORCEPROP 1 LAST PATH I52
J 0
(-2275 3675);
DISPLAY 0.978723 (-2275 3675);
PAINT WHITE (-2275 3675);
DISPLAY INVISIBLE (-2275 3675);
FORCEPROP 1 LAST PART_NUMBER CH5471MEB01
J 0
(-2275 3375);
DISPLAY 0.978723 (-2275 3375);
DISPLAY INVISIBLE (-2275 3375);
FORCEADD Q_CAP..1
(-2100 3525);
FORCEPROP 1 LAST LOCATION C491
J 0
(-2050 3625);
DISPLAY 0.978723 (-2050 3625);
PAINT WHITE (-2050 3625);
FORCEPROP 0 LAST $SEC 1
J 0
(-2050 3675);
DISPLAY 0.680851 (-2050 3675);
PAINT MONO (-2050 3675);
DISPLAY INVISIBLE (-2050 3675);
FORCEPROP 0 LAST CDS_SEC 1
J 0
(-2050 3675);
DISPLAY 0.680851 (-2050 3675);
DISPLAY INVISIBLE (-2050 3675);
FORCEPROP 1 LASTPIN (-2100 3625) $PN 1
J 0
(-2090 3605);
DISPLAY 0.787234 (-2090 3605);
PAINT MONO (-2090 3605);
FORCEPROP 1 LASTPIN (-2100 3425) $PN 2
J 0
(-2090 3405);
DISPLAY 0.787234 (-2090 3405);
PAINT MONO (-2090 3405);
FORCEPROP 1 LAST PACK_TYPE 0201
J 0
(-2050 3375);
DISPLAY 0.510638 (-2050 3375);
FORCEPROP 1 LAST MATERIAL X6S
J 0
(-2050 3425);
DISPLAY 0.510638 (-2050 3425);
FORCEPROP 1 LAST VALUE 1UF
J 0
(-2050 3575);
DISPLAY 0.510638 (-2050 3575);
FORCEPROP 1 LAST TOLERANCE 20%
J 0
(-2050 3475);
DISPLAY 0.510638 (-2050 3475);
FORCEPROP 1 LAST VOLTAGE 4V
J 0
(-2050 3525);
DISPLAY 0.510638 (-2050 3525);
FORCEPROP 2 LAST CDS_LIB pure_quanta
J 0
(-2100 3525);
DISPLAY INVISIBLE (-2100 3525);
FORCEPROP 1 LAST PATH I53
J 0
(-2050 3675);
DISPLAY 0.978723 (-2050 3675);
PAINT WHITE (-2050 3675);
DISPLAY INVISIBLE (-2050 3675);
FORCEPROP 1 LAST PART_NUMBER CH-10KMEE00
J 0
(-2050 3375);
DISPLAY 0.510638 (-2050 3375);
DISPLAY INVISIBLE (-2050 3375);
FORCEADD Q_CAP..1
(-2075 2875);
FORCEPROP 1 LAST LOCATION C492
J 0
(-2025 2975);
DISPLAY 0.978723 (-2025 2975);
PAINT WHITE (-2025 2975);
FORCEPROP 0 LAST $SEC 1
J 0
(-2025 3025);
DISPLAY 0.680851 (-2025 3025);
PAINT MONO (-2025 3025);
DISPLAY INVISIBLE (-2025 3025);
FORCEPROP 0 LAST CDS_SEC 1
J 0
(-2025 3025);
DISPLAY 0.680851 (-2025 3025);
DISPLAY INVISIBLE (-2025 3025);
FORCEPROP 1 LASTPIN (-2075 2975) $PN 1
J 0
(-2065 2955);
DISPLAY 0.787234 (-2065 2955);
PAINT MONO (-2065 2955);
FORCEPROP 1 LASTPIN (-2075 2775) $PN 2
J 0
(-2065 2755);
DISPLAY 0.787234 (-2065 2755);
PAINT MONO (-2065 2755);
FORCEPROP 1 LAST MATERIAL X6S
J 0
(-2025 2775);
DISPLAY 0.510638 (-2025 2775);
FORCEPROP 1 LAST VALUE 1UF
J 0
(-2025 2925);
DISPLAY 0.510638 (-2025 2925);
FORCEPROP 1 LAST PACK_TYPE 0201
J 0
(-2025 2725);
DISPLAY 0.510638 (-2025 2725);
FORCEPROP 1 LAST TOLERANCE 20%
J 0
(-2025 2825);
DISPLAY 0.510638 (-2025 2825);
FORCEPROP 1 LAST VOLTAGE 4V
J 0
(-2025 2875);
DISPLAY 0.510638 (-2025 2875);
FORCEPROP 2 LAST CDS_LIB pure_quanta
J 0
(-2075 2875);
DISPLAY INVISIBLE (-2075 2875);
FORCEPROP 1 LAST PATH I54
J 0
(-2025 3025);
DISPLAY 0.978723 (-2025 3025);
PAINT WHITE (-2025 3025);
DISPLAY INVISIBLE (-2025 3025);
FORCEPROP 1 LAST PART_NUMBER CH-10KMEE00
J 0
(-2025 2725);
DISPLAY 0.510638 (-2025 2725);
DISPLAY INVISIBLE (-2025 2725);
FORCEADD UNIVERSAL_GND..1
(-1375 1775);
FORCEPROP 3 LASTPIN (-1375 1825) SIG_NAME GND\g
J 0
(-1365 1835);
DISPLAY 0.659574 (-1365 1835);
PAINT MONO (-1365 1835);
DISPLAY INVISIBLE (-1365 1835);
FORCEPROP 2 LAST CDS_LIB pure_quanta_power
J 0
(-1375 1775);
DISPLAY INVISIBLE (-1375 1775);
FORCEPROP 1 LAST HDL_POWER GND
J 1
(-1350 1700);
DISPLAY 0.872340 (-1350 1700);
PAINT GREEN (-1350 1700);
DISPLAY INVISIBLE (-1350 1700);
FORCEPROP 1 LAST PATH I55
J 0
(-1300 1775);
DISPLAY 0.872340 (-1300 1775);
PAINT AQUA (-1300 1775);
DISPLAY INVISIBLE (-1300 1775);
FORCEADD Q_CAP..1
(-1900 2200);
FORCEPROP 1 LAST LOCATION C481
J 0
(-1850 2300);
DISPLAY 0.978723 (-1850 2300);
PAINT WHITE (-1850 2300);
FORCEPROP 0 LAST $SEC 1
J 0
(-1850 2350);
DISPLAY 0.680851 (-1850 2350);
PAINT MONO (-1850 2350);
DISPLAY INVISIBLE (-1850 2350);
FORCEPROP 0 LAST CDS_SEC 1
J 0
(-1850 2350);
DISPLAY 0.680851 (-1850 2350);
DISPLAY INVISIBLE (-1850 2350);
FORCEPROP 1 LASTPIN (-1900 2300) $PN 1
J 0
(-1890 2280);
DISPLAY 0.787234 (-1890 2280);
PAINT MONO (-1890 2280);
FORCEPROP 1 LASTPIN (-1900 2100) $PN 2
J 0
(-1890 2080);
DISPLAY 0.787234 (-1890 2080);
PAINT MONO (-1890 2080);
FORCEPROP 1 LAST PACK_TYPE C0201
J 0
(-1850 2050);
DISPLAY 0.638298 (-1850 2050);
FORCEPROP 1 LAST VALUE 0.1UF
J 0
(-1850 2250);
DISPLAY 0.638298 (-1850 2250);
FORCEPROP 1 LAST MATERIAL X7S
J 0
(-1850 2100);
DISPLAY 0.638298 (-1850 2100);
FORCEPROP 1 LAST TOLERANCE 10%
J 0
(-1850 2150);
DISPLAY 0.638298 (-1850 2150);
FORCEPROP 1 LAST VOLTAGE 10V
J 0
(-1850 2200);
DISPLAY 0.638298 (-1850 2200);
FORCEPROP 2 LAST CDS_LIB pure_quanta
J 0
(-1900 2200);
DISPLAY INVISIBLE (-1900 2200);
FORCEPROP 1 LAST PATH I56
J 0
(-1850 2350);
DISPLAY 0.978723 (-1850 2350);
PAINT WHITE (-1850 2350);
DISPLAY INVISIBLE (-1850 2350);
FORCEPROP 1 LAST PART_NUMBER CH4102K6E00
J 0
(-1850 2050);
DISPLAY 0.978723 (-1850 2050);
DISPLAY INVISIBLE (-1850 2050);
FORCEADD Q_CAP..1
(-1625 2200);
FORCEPROP 1 LAST LOCATION C457
J 0
(-1575 2300);
DISPLAY 0.978723 (-1575 2300);
PAINT WHITE (-1575 2300);
FORCEPROP 0 LAST $SEC 1
J 0
(-1575 2350);
DISPLAY 0.680851 (-1575 2350);
PAINT MONO (-1575 2350);
DISPLAY INVISIBLE (-1575 2350);
FORCEPROP 0 LAST CDS_SEC 1
J 0
(-1575 2350);
DISPLAY 0.680851 (-1575 2350);
DISPLAY INVISIBLE (-1575 2350);
FORCEPROP 1 LASTPIN (-1625 2300) $PN 1
J 0
(-1615 2280);
DISPLAY 0.787234 (-1615 2280);
PAINT MONO (-1615 2280);
FORCEPROP 1 LASTPIN (-1625 2100) $PN 2
J 0
(-1615 2080);
DISPLAY 0.787234 (-1615 2080);
PAINT MONO (-1615 2080);
FORCEPROP 1 LAST MATERIAL X7S
J 0
(-1575 2100);
DISPLAY 0.638298 (-1575 2100);
FORCEPROP 1 LAST VALUE 0.1UF
J 0
(-1575 2250);
DISPLAY 0.638298 (-1575 2250);
FORCEPROP 1 LAST PACK_TYPE C0201
J 0
(-1575 2050);
DISPLAY 0.638298 (-1575 2050);
FORCEPROP 1 LAST TOLERANCE 10%
J 0
(-1575 2150);
DISPLAY 0.638298 (-1575 2150);
FORCEPROP 1 LAST VOLTAGE 10V
J 0
(-1575 2200);
DISPLAY 0.638298 (-1575 2200);
FORCEPROP 2 LAST CDS_LIB pure_quanta
J 0
(-1625 2200);
DISPLAY INVISIBLE (-1625 2200);
FORCEPROP 1 LAST PATH I57
J 0
(-1575 2350);
DISPLAY 0.978723 (-1575 2350);
PAINT WHITE (-1575 2350);
DISPLAY INVISIBLE (-1575 2350);
FORCEPROP 1 LAST PART_NUMBER CH4102K6E00
J 0
(-1575 2050);
DISPLAY 0.978723 (-1575 2050);
DISPLAY INVISIBLE (-1575 2050);
FORCEADD Q_CAP..1
(-6500 3050);
FORCEPROP 1 LAST LOCATION C444
J 0
(-6450 3150);
DISPLAY 0.978723 (-6450 3150);
PAINT WHITE (-6450 3150);
FORCEPROP 0 LAST $SEC 1
J 0
(-6450 3200);
DISPLAY 0.680851 (-6450 3200);
PAINT MONO (-6450 3200);
DISPLAY INVISIBLE (-6450 3200);
FORCEPROP 0 LAST CDS_SEC 1
J 0
(-6450 3200);
DISPLAY 0.680851 (-6450 3200);
DISPLAY INVISIBLE (-6450 3200);
FORCEPROP 1 LASTPIN (-6500 3150) $PN 1
J 0
(-6490 3130);
DISPLAY 0.787234 (-6490 3130);
PAINT MONO (-6490 3130);
FORCEPROP 1 LASTPIN (-6500 2950) $PN 2
J 0
(-6490 2930);
DISPLAY 0.787234 (-6490 2930);
PAINT MONO (-6490 2930);
FORCEPROP 1 LAST PACK_TYPE C0201
J 0
(-6450 2900);
DISPLAY 0.638298 (-6450 2900);
FORCEPROP 1 LAST MATERIAL X7S
J 0
(-6450 2950);
DISPLAY 0.638298 (-6450 2950);
FORCEPROP 1 LAST VOLTAGE 10V
J 0
(-6450 3050);
DISPLAY 0.638298 (-6450 3050);
FORCEPROP 1 LAST VALUE 0.1UF
J 0
(-6450 3100);
DISPLAY 0.638298 (-6450 3100);
FORCEPROP 1 LAST TOLERANCE 10%
J 0
(-6450 3000);
DISPLAY 0.638298 (-6450 3000);
FORCEPROP 2 LAST CDS_LIB pure_quanta
J 0
(-6500 3050);
DISPLAY INVISIBLE (-6500 3050);
FORCEPROP 1 LAST PATH I6
J 0
(-6450 3200);
DISPLAY 0.978723 (-6450 3200);
PAINT WHITE (-6450 3200);
DISPLAY INVISIBLE (-6450 3200);
FORCEPROP 1 LAST PART_NUMBER CH4102K6E00
J 0
(-6450 2900);
DISPLAY 0.978723 (-6450 2900);
DISPLAY INVISIBLE (-6450 2900);
FORCEADD Q_CAP..1
(-1650 3525);
FORCEPROP 1 LAST LOCATION C497
J 0
(-1600 3625);
DISPLAY 0.978723 (-1600 3625);
PAINT WHITE (-1600 3625);
FORCEPROP 0 LAST $SEC 1
J 0
(-1600 3675);
DISPLAY 0.680851 (-1600 3675);
PAINT MONO (-1600 3675);
DISPLAY INVISIBLE (-1600 3675);
FORCEPROP 0 LAST CDS_SEC 1
J 0
(-1600 3675);
DISPLAY 0.680851 (-1600 3675);
DISPLAY INVISIBLE (-1600 3675);
FORCEPROP 1 LASTPIN (-1650 3625) $PN 1
J 0
(-1640 3605);
DISPLAY 0.787234 (-1640 3605);
PAINT MONO (-1640 3605);
FORCEPROP 1 LASTPIN (-1650 3425) $PN 2
J 0
(-1640 3405);
DISPLAY 0.787234 (-1640 3405);
PAINT MONO (-1640 3405);
FORCEPROP 1 LAST MATERIAL X6S
J 0
(-1600 3425);
DISPLAY 0.510638 (-1600 3425);
FORCEPROP 1 LAST PACK_TYPE 0201
J 0
(-1600 3375);
DISPLAY 0.510638 (-1600 3375);
FORCEPROP 1 LAST VALUE 1UF
J 0
(-1600 3575);
DISPLAY 0.510638 (-1600 3575);
FORCEPROP 1 LAST TOLERANCE 20%
J 0
(-1600 3475);
DISPLAY 0.510638 (-1600 3475);
FORCEPROP 1 LAST VOLTAGE 4V
J 0
(-1600 3525);
DISPLAY 0.510638 (-1600 3525);
FORCEPROP 2 LAST CDS_LIB pure_quanta
J 0
(-1650 3525);
DISPLAY INVISIBLE (-1650 3525);
FORCEPROP 1 LAST PATH I60
J 0
(-1600 3675);
DISPLAY 0.978723 (-1600 3675);
PAINT WHITE (-1600 3675);
DISPLAY INVISIBLE (-1600 3675);
FORCEPROP 1 LAST PART_NUMBER CH-10KMEE00
J 0
(-1600 3375);
DISPLAY 0.510638 (-1600 3375);
DISPLAY INVISIBLE (-1600 3375);
FORCEADD Q_CAP..1
(-1400 3525);
FORCEPROP 1 LAST LOCATION C455
J 0
(-1350 3625);
DISPLAY 0.978723 (-1350 3625);
PAINT WHITE (-1350 3625);
FORCEPROP 0 LAST $SEC 1
J 0
(-1350 3675);
DISPLAY 0.680851 (-1350 3675);
PAINT MONO (-1350 3675);
DISPLAY INVISIBLE (-1350 3675);
FORCEPROP 0 LAST CDS_SEC 1
J 0
(-1350 3675);
DISPLAY 0.680851 (-1350 3675);
DISPLAY INVISIBLE (-1350 3675);
FORCEPROP 1 LASTPIN (-1400 3625) $PN 1
J 0
(-1390 3605);
DISPLAY 0.787234 (-1390 3605);
PAINT MONO (-1390 3605);
FORCEPROP 1 LASTPIN (-1400 3425) $PN 2
J 0
(-1390 3405);
DISPLAY 0.787234 (-1390 3405);
PAINT MONO (-1390 3405);
FORCEPROP 1 LAST TOLERANCE 20%
J 0
(-1350 3475);
DISPLAY 0.510638 (-1350 3475);
FORCEPROP 1 LAST MATERIAL X6S
J 0
(-1350 3425);
DISPLAY 0.510638 (-1350 3425);
FORCEPROP 1 LAST VALUE 1UF
J 0
(-1350 3575);
DISPLAY 0.510638 (-1350 3575);
FORCEPROP 1 LAST VOLTAGE 4V
J 0
(-1350 3525);
DISPLAY 0.510638 (-1350 3525);
FORCEPROP 1 LAST PACK_TYPE 0201
J 0
(-1350 3375);
DISPLAY 0.510638 (-1350 3375);
FORCEPROP 2 LAST CDS_LIB pure_quanta
J 0
(-1400 3525);
DISPLAY INVISIBLE (-1400 3525);
FORCEPROP 1 LAST PATH I61
J 0
(-1350 3675);
DISPLAY 0.978723 (-1350 3675);
PAINT WHITE (-1350 3675);
DISPLAY INVISIBLE (-1350 3675);
FORCEPROP 1 LAST PART_NUMBER CH-10KMEE00
J 0
(-1350 3375);
DISPLAY 0.510638 (-1350 3375);
DISPLAY INVISIBLE (-1350 3375);
FORCEADD UNIVERSAL_GND..1
(-875 2475);
FORCEPROP 3 LASTPIN (-875 2525) SIG_NAME GND\g
J 0
(-865 2535);
DISPLAY 0.659574 (-865 2535);
PAINT MONO (-865 2535);
DISPLAY INVISIBLE (-865 2535);
FORCEPROP 2 LAST CDS_LIB pure_quanta_power
J 0
(-875 2475);
DISPLAY INVISIBLE (-875 2475);
FORCEPROP 1 LAST HDL_POWER GND
J 1
(-850 2400);
DISPLAY 0.872340 (-850 2400);
PAINT GREEN (-850 2400);
DISPLAY INVISIBLE (-850 2400);
FORCEPROP 1 LAST PATH I62
J 0
(-800 2475);
DISPLAY 0.872340 (-800 2475);
PAINT AQUA (-800 2475);
DISPLAY INVISIBLE (-800 2475);
FORCEADD Q_INDUCTOR..1
(-3825 4425);
FORCEPROP 1 LAST LOCATION L10
J 0
(-3950 4585);
DISPLAY 0.723404 (-3950 4585);
PAINT GREEN (-3950 4585);
FORCEPROP 0 LAST $SEC 1
J 0
(-3950 4725);
DISPLAY 0.680851 (-3950 4725);
PAINT MONO (-3950 4725);
DISPLAY INVISIBLE (-3950 4725);
FORCEPROP 0 LAST CDS_SEC 1
J 0
(-3950 4725);
DISPLAY 0.680851 (-3950 4725);
DISPLAY INVISIBLE (-3950 4725);
FORCEPROP 0 LASTPIN (-3925 4400) $PN 1
J 2
(-3935 4410);
DISPLAY 0.680851 (-3935 4410);
PAINT MONO (-3935 4410);
FORCEPROP 0 LASTPIN (-3725 4400) $PN 2
J 0
(-3715 4410);
DISPLAY 0.680851 (-3715 4410);
PAINT MONO (-3715 4410);
FORCEPROP 2 LAST VALUE 100NH/16A
J 0
(-3950 4675);
DISPLAY 0.680851 (-3950 4675);
FORCEPROP 2 LAST PACK_TYPE SMLF
J 0
(-3950 4625);
DISPLAY 0.680851 (-3950 4625);
FORCEPROP 1 LAST MATERIAL IND
J 0
(-3950 4480);
DISPLAY 0.723404 (-3950 4480);
PAINT GREEN (-3950 4480);
FORCEPROP 1 LAST NEEDS_NO_SIZE TRUE
J 0
(-3825 4425);
DISPLAY 0.468085 (-3825 4425);
PAINT GREEN (-3825 4425);
DISPLAY INVISIBLE (-3825 4425);
FORCEPROP 2 LAST CDS_LIB pure_quanta
J 0
(-3825 4425);
DISPLAY INVISIBLE (-3825 4425);
FORCEPROP 1 LAST PATH I63
J 0
(-3750 4480);
DISPLAY 0.723404 (-3750 4480);
PAINT GREEN (-3750 4480);
DISPLAY INVISIBLE (-3750 4480);
FORCEPROP 1 LAST PART_NUMBER CV+10G0MZ04
J 0
(-3950 4535);
DISPLAY 0.723404 (-3950 4535);
PAINT GREEN (-3950 4535);
DISPLAY INVISIBLE (-3950 4535);
FORCEADD Q_CAP..1
(-3475 4150);
FORCEPROP 1 LAST LOCATION C466
J 0
(-3425 4250);
DISPLAY 0.978723 (-3425 4250);
PAINT WHITE (-3425 4250);
FORCEPROP 0 LAST $SEC 1
J 0
(-3425 4300);
DISPLAY 0.680851 (-3425 4300);
PAINT MONO (-3425 4300);
DISPLAY INVISIBLE (-3425 4300);
FORCEPROP 0 LAST CDS_SEC 1
J 0
(-3425 4300);
DISPLAY 0.680851 (-3425 4300);
DISPLAY INVISIBLE (-3425 4300);
FORCEPROP 1 LASTPIN (-3475 4250) $PN 1
J 0
(-3465 4230);
DISPLAY 0.787234 (-3465 4230);
PAINT MONO (-3465 4230);
FORCEPROP 1 LASTPIN (-3475 4050) $PN 2
J 0
(-3465 4030);
DISPLAY 0.787234 (-3465 4030);
PAINT MONO (-3465 4030);
FORCEPROP 1 LAST VALUE 100UF
J 0
(-3425 4200);
DISPLAY 0.510638 (-3425 4200);
FORCEPROP 1 LAST VOLTAGE 4V
J 0
(-3425 4150);
DISPLAY 0.510638 (-3425 4150);
FORCEPROP 1 LAST PACK_TYPE C0805
J 0
(-3425 4000);
DISPLAY 0.510638 (-3425 4000);
FORCEPROP 1 LAST TOLERANCE 20%
J 0
(-3425 4100);
DISPLAY 0.510638 (-3425 4100);
FORCEPROP 1 LAST MATERIAL X6S
J 0
(-3425 4050);
DISPLAY 0.510638 (-3425 4050);
FORCEPROP 2 LAST CDS_LIB pure_quanta
J 0
(-3475 4150);
DISPLAY INVISIBLE (-3475 4150);
FORCEPROP 1 LAST PATH I64
J 0
(-3425 4300);
DISPLAY 0.978723 (-3425 4300);
PAINT WHITE (-3425 4300);
DISPLAY INVISIBLE (-3425 4300);
FORCEPROP 1 LAST PART_NUMBER CH710KMEA01
J 0
(-3425 4000);
DISPLAY 0.404255 (-3425 4000);
DISPLAY INVISIBLE (-3425 4000);
FORCEADD Q_CAP..1
(-3250 4150);
FORCEPROP 1 LAST LOCATION C471
J 0
(-3200 4250);
DISPLAY 0.978723 (-3200 4250);
PAINT WHITE (-3200 4250);
FORCEPROP 0 LAST $SEC 1
J 0
(-3200 4300);
DISPLAY 0.680851 (-3200 4300);
PAINT MONO (-3200 4300);
DISPLAY INVISIBLE (-3200 4300);
FORCEPROP 0 LAST CDS_SEC 1
J 0
(-3200 4300);
DISPLAY 0.680851 (-3200 4300);
DISPLAY INVISIBLE (-3200 4300);
FORCEPROP 1 LASTPIN (-3250 4250) $PN 1
J 0
(-3240 4230);
DISPLAY 0.787234 (-3240 4230);
PAINT MONO (-3240 4230);
FORCEPROP 1 LASTPIN (-3250 4050) $PN 2
J 0
(-3240 4030);
DISPLAY 0.787234 (-3240 4030);
PAINT MONO (-3240 4030);
FORCEPROP 1 LAST TOLERANCE 20%
J 0
(-3200 4100);
DISPLAY 0.510638 (-3200 4100);
FORCEPROP 1 LAST VOLTAGE 4V
J 0
(-3200 4150);
DISPLAY 0.510638 (-3200 4150);
FORCEPROP 1 LAST PACK_TYPE C0805
J 0
(-3200 4000);
DISPLAY 0.510638 (-3200 4000);
FORCEPROP 1 LAST VALUE 100UF
J 0
(-3200 4200);
DISPLAY 0.510638 (-3200 4200);
FORCEPROP 1 LAST MATERIAL X6S
J 0
(-3200 4050);
DISPLAY 0.510638 (-3200 4050);
FORCEPROP 2 LAST CDS_LIB pure_quanta
J 0
(-3250 4150);
DISPLAY INVISIBLE (-3250 4150);
FORCEPROP 1 LAST PATH I65
J 0
(-3200 4300);
DISPLAY 0.978723 (-3200 4300);
PAINT WHITE (-3200 4300);
DISPLAY INVISIBLE (-3200 4300);
FORCEPROP 1 LAST PART_NUMBER CH710KMEA01
J 0
(-3200 4000);
DISPLAY 0.404255 (-3200 4000);
DISPLAY INVISIBLE (-3200 4000);
FORCEADD VCC_CORE..1
(-3475 4800);
FORCEPROP 3 LASTPIN (-3475 4750) SIG_NAME P0V9_CPU1_RT3_2A\g
J 0
(-3465 4760);
DISPLAY 0.659574 (-3465 4760);
PAINT MONO (-3465 4760);
DISPLAY INVISIBLE (-3465 4760);
FORCEPROP 1 LAST HDL_POWER P0V9_CPU1_RT3_2A
J 1
(-3475 4850);
DISPLAY 0.617021 (-3475 4850);
PAINT GREEN (-3475 4850);
FORCEPROP 2 LAST CDS_LIB pure_quanta_power
J 0
(-3475 4800);
DISPLAY INVISIBLE (-3475 4800);
FORCEPROP 1 LAST PATH I66
J 0
(-3425 4825);
DISPLAY 0.872340 (-3425 4825);
PAINT AQUA (-3425 4825);
DISPLAY INVISIBLE (-3425 4825);
FORCEADD Q_CAP..1
(-3425 5425);
FORCEPROP 1 LAST LOCATION C474
J 0
(-3375 5525);
DISPLAY 0.978723 (-3375 5525);
PAINT WHITE (-3375 5525);
FORCEPROP 0 LAST $SEC 1
J 0
(-3375 5575);
DISPLAY 0.680851 (-3375 5575);
PAINT MONO (-3375 5575);
DISPLAY INVISIBLE (-3375 5575);
FORCEPROP 0 LAST CDS_SEC 1
J 0
(-3375 5575);
DISPLAY 0.680851 (-3375 5575);
DISPLAY INVISIBLE (-3375 5575);
FORCEPROP 1 LASTPIN (-3425 5525) $PN 1
J 0
(-3415 5505);
DISPLAY 0.787234 (-3415 5505);
PAINT MONO (-3415 5505);
FORCEPROP 1 LASTPIN (-3425 5325) $PN 2
J 0
(-3415 5305);
DISPLAY 0.787234 (-3415 5305);
PAINT MONO (-3415 5305);
FORCEPROP 1 LAST MATERIAL X6S
J 0
(-3375 5325);
DISPLAY 0.510638 (-3375 5325);
FORCEPROP 1 LAST PACK_TYPE C0805
J 0
(-3375 5275);
DISPLAY 0.510638 (-3375 5275);
FORCEPROP 1 LAST TOLERANCE 20%
J 0
(-3375 5375);
DISPLAY 0.510638 (-3375 5375);
FORCEPROP 1 LAST VOLTAGE 4V
J 0
(-3375 5425);
DISPLAY 0.510638 (-3375 5425);
FORCEPROP 1 LAST VALUE 100UF
J 0
(-3375 5475);
DISPLAY 0.510638 (-3375 5475);
FORCEPROP 2 LAST CDS_LIB pure_quanta
J 0
(-3425 5425);
DISPLAY INVISIBLE (-3425 5425);
FORCEPROP 1 LAST PATH I67
J 0
(-3375 5575);
DISPLAY 0.978723 (-3375 5575);
PAINT WHITE (-3375 5575);
DISPLAY INVISIBLE (-3375 5575);
FORCEPROP 1 LAST PART_NUMBER CH710KMEA01
J 0
(-3375 5275);
DISPLAY 0.404255 (-3375 5275);
DISPLAY INVISIBLE (-3375 5275);
FORCEADD Q_CAP..1
(-3150 5425);
FORCEPROP 1 LAST LOCATION C478
J 0
(-3100 5525);
DISPLAY 0.978723 (-3100 5525);
PAINT WHITE (-3100 5525);
FORCEPROP 0 LAST $SEC 1
J 0
(-3100 5575);
DISPLAY 0.680851 (-3100 5575);
PAINT MONO (-3100 5575);
DISPLAY INVISIBLE (-3100 5575);
FORCEPROP 0 LAST CDS_SEC 1
J 0
(-3100 5575);
DISPLAY 0.680851 (-3100 5575);
DISPLAY INVISIBLE (-3100 5575);
FORCEPROP 1 LASTPIN (-3150 5525) $PN 1
J 0
(-3140 5505);
DISPLAY 0.787234 (-3140 5505);
PAINT MONO (-3140 5505);
FORCEPROP 1 LASTPIN (-3150 5325) $PN 2
J 0
(-3140 5305);
DISPLAY 0.787234 (-3140 5305);
PAINT MONO (-3140 5305);
FORCEPROP 1 LAST TOLERANCE 20%
J 0
(-3100 5375);
DISPLAY 0.510638 (-3100 5375);
FORCEPROP 1 LAST PACK_TYPE C0402
J 0
(-3100 5275);
DISPLAY 0.510638 (-3100 5275);
FORCEPROP 1 LAST MATERIAL X6S
J 0
(-3100 5325);
DISPLAY 0.510638 (-3100 5325);
FORCEPROP 1 LAST VOLTAGE 4V
J 0
(-3100 5425);
DISPLAY 0.510638 (-3100 5425);
FORCEPROP 1 LAST VALUE 22UF
J 0
(-3100 5475);
DISPLAY 0.510638 (-3100 5475);
FORCEPROP 2 LAST CDS_LIB pure_quanta
J 0
(-3150 5425);
DISPLAY INVISIBLE (-3150 5425);
FORCEPROP 1 LAST PATH I68
J 0
(-3100 5575);
DISPLAY 0.978723 (-3100 5575);
PAINT WHITE (-3100 5575);
DISPLAY INVISIBLE (-3100 5575);
FORCEPROP 1 LAST PART_NUMBER CH622KMEB02
J 0
(-3100 5275);
DISPLAY 0.978723 (-3100 5275);
DISPLAY INVISIBLE (-3100 5275);
FORCEADD Q_CAP..1
(-3025 4150);
FORCEPROP 1 LAST LOCATION C475
J 0
(-2975 4250);
DISPLAY 0.978723 (-2975 4250);
PAINT WHITE (-2975 4250);
FORCEPROP 0 LAST $SEC 1
J 0
(-2975 4300);
DISPLAY 0.680851 (-2975 4300);
PAINT MONO (-2975 4300);
DISPLAY INVISIBLE (-2975 4300);
FORCEPROP 0 LAST CDS_SEC 1
J 0
(-2975 4300);
DISPLAY 0.680851 (-2975 4300);
DISPLAY INVISIBLE (-2975 4300);
FORCEPROP 1 LASTPIN (-3025 4250) $PN 1
J 0
(-3015 4230);
DISPLAY 0.787234 (-3015 4230);
PAINT MONO (-3015 4230);
FORCEPROP 1 LASTPIN (-3025 4050) $PN 2
J 0
(-3015 4030);
DISPLAY 0.787234 (-3015 4030);
PAINT MONO (-3015 4030);
FORCEPROP 1 LAST PACK_TYPE C0805
J 0
(-2975 4000);
DISPLAY 0.510638 (-2975 4000);
FORCEPROP 1 LAST TOLERANCE 20%
J 0
(-2975 4100);
DISPLAY 0.510638 (-2975 4100);
FORCEPROP 1 LAST MATERIAL X6S
J 0
(-2975 4050);
DISPLAY 0.510638 (-2975 4050);
FORCEPROP 1 LAST VOLTAGE 4V
J 0
(-2975 4150);
DISPLAY 0.510638 (-2975 4150);
FORCEPROP 1 LAST VALUE 100UF
J 0
(-2975 4200);
DISPLAY 0.510638 (-2975 4200);
FORCEPROP 2 LAST CDS_LIB pure_quanta
J 0
(-3025 4150);
DISPLAY INVISIBLE (-3025 4150);
FORCEPROP 1 LAST PATH I69
J 0
(-2975 4300);
DISPLAY 0.978723 (-2975 4300);
PAINT WHITE (-2975 4300);
DISPLAY INVISIBLE (-2975 4300);
FORCEPROP 1 LAST PART_NUMBER CH710KMEA01
J 0
(-2975 4000);
DISPLAY 0.404255 (-2975 4000);
DISPLAY INVISIBLE (-2975 4000);
FORCEADD UNIVERSAL_GND..1
(-6150 3825);
FORCEPROP 3 LASTPIN (-6150 3875) SIG_NAME GND\g
J 0
(-6140 3885);
DISPLAY 0.659574 (-6140 3885);
PAINT MONO (-6140 3885);
DISPLAY INVISIBLE (-6140 3885);
FORCEPROP 2 LAST CDS_LIB pure_quanta_power
J 0
(-6150 3825);
DISPLAY INVISIBLE (-6150 3825);
FORCEPROP 1 LAST HDL_POWER GND
J 1
(-6125 3750);
DISPLAY 0.872340 (-6125 3750);
PAINT GREEN (-6125 3750);
DISPLAY INVISIBLE (-6125 3750);
FORCEPROP 1 LAST PATH I7
J 0
(-6075 3825);
DISPLAY 0.872340 (-6075 3825);
PAINT AQUA (-6075 3825);
DISPLAY INVISIBLE (-6075 3825);
FORCEADD Q_CAP..1
(-2550 4150);
FORCEPROP 1 LAST LOCATION C501
J 0
(-2500 4250);
DISPLAY 0.978723 (-2500 4250);
PAINT WHITE (-2500 4250);
FORCEPROP 0 LAST $SEC 1
J 0
(-2500 4300);
DISPLAY 0.680851 (-2500 4300);
PAINT MONO (-2500 4300);
DISPLAY INVISIBLE (-2500 4300);
FORCEPROP 0 LAST CDS_SEC 1
J 0
(-2500 4300);
DISPLAY 0.680851 (-2500 4300);
DISPLAY INVISIBLE (-2500 4300);
FORCEPROP 1 LASTPIN (-2550 4250) $PN 1
J 0
(-2540 4230);
DISPLAY 0.787234 (-2540 4230);
PAINT MONO (-2540 4230);
FORCEPROP 1 LASTPIN (-2550 4050) $PN 2
J 0
(-2540 4030);
DISPLAY 0.787234 (-2540 4030);
PAINT MONO (-2540 4030);
FORCEPROP 1 LAST MATERIAL X6S
J 0
(-2500 4050);
DISPLAY 0.510638 (-2500 4050);
FORCEPROP 1 LAST PACK_TYPE C0402
J 0
(-2500 4000);
DISPLAY 0.510638 (-2500 4000);
FORCEPROP 1 LAST VOLTAGE 4V
J 0
(-2500 4150);
DISPLAY 0.510638 (-2500 4150);
FORCEPROP 1 LAST TOLERANCE 20%
J 0
(-2500 4100);
DISPLAY 0.510638 (-2500 4100);
FORCEPROP 1 LAST VALUE 22UF
J 0
(-2500 4200);
DISPLAY 0.510638 (-2500 4200);
FORCEPROP 2 LAST CDS_LIB pure_quanta
J 0
(-2550 4150);
DISPLAY INVISIBLE (-2550 4150);
FORCEPROP 1 LAST PATH I70
J 0
(-2500 4300);
DISPLAY 0.978723 (-2500 4300);
PAINT WHITE (-2500 4300);
DISPLAY INVISIBLE (-2500 4300);
FORCEPROP 1 LAST PART_NUMBER CH622KMEB02
J 0
(-2500 4000);
DISPLAY 0.978723 (-2500 4000);
DISPLAY INVISIBLE (-2500 4000);
FORCEADD Q_CAP..1
(-2100 4150);
FORCEPROP 1 LAST LOCATION C476
J 0
(-2050 4250);
DISPLAY 0.978723 (-2050 4250);
PAINT WHITE (-2050 4250);
FORCEPROP 0 LAST $SEC 1
J 0
(-2050 4300);
DISPLAY 0.680851 (-2050 4300);
PAINT MONO (-2050 4300);
DISPLAY INVISIBLE (-2050 4300);
FORCEPROP 0 LAST CDS_SEC 1
J 0
(-2050 4300);
DISPLAY 0.680851 (-2050 4300);
DISPLAY INVISIBLE (-2050 4300);
FORCEPROP 1 LASTPIN (-2100 4250) $PN 1
J 0
(-2090 4230);
DISPLAY 0.787234 (-2090 4230);
PAINT MONO (-2090 4230);
FORCEPROP 1 LASTPIN (-2100 4050) $PN 2
J 0
(-2090 4030);
DISPLAY 0.787234 (-2090 4030);
PAINT MONO (-2090 4030);
FORCEPROP 1 LAST PACK_TYPE C0402
J 0
(-2050 4000);
DISPLAY 0.510638 (-2050 4000);
FORCEPROP 1 LAST MATERIAL X6S
J 0
(-2050 4050);
DISPLAY 0.510638 (-2050 4050);
FORCEPROP 1 LAST TOLERANCE 20%
J 0
(-2050 4100);
DISPLAY 0.510638 (-2050 4100);
FORCEPROP 1 LAST VOLTAGE 4V
J 0
(-2050 4150);
DISPLAY 0.510638 (-2050 4150);
FORCEPROP 1 LAST VALUE 22UF
J 0
(-2050 4200);
DISPLAY 0.510638 (-2050 4200);
FORCEPROP 2 LAST CDS_LIB pure_quanta
J 0
(-2100 4150);
DISPLAY INVISIBLE (-2100 4150);
FORCEPROP 1 LAST PATH I71
J 0
(-2050 4300);
DISPLAY 0.978723 (-2050 4300);
PAINT WHITE (-2050 4300);
DISPLAY INVISIBLE (-2050 4300);
FORCEPROP 1 LAST PART_NUMBER CH622KMEB02
J 0
(-2050 4000);
DISPLAY 0.978723 (-2050 4000);
DISPLAY INVISIBLE (-2050 4000);
FORCEADD Q_CAP..1
(-2825 5400);
FORCEPROP 1 LAST LOCATION C489
J 0
(-2775 5500);
DISPLAY 0.978723 (-2775 5500);
PAINT WHITE (-2775 5500);
FORCEPROP 0 LAST $SEC 1
J 0
(-2775 5550);
DISPLAY 0.680851 (-2775 5550);
PAINT MONO (-2775 5550);
DISPLAY INVISIBLE (-2775 5550);
FORCEPROP 0 LAST CDS_SEC 1
J 0
(-2775 5550);
DISPLAY 0.680851 (-2775 5550);
DISPLAY INVISIBLE (-2775 5550);
FORCEPROP 1 LASTPIN (-2825 5500) $PN 1
J 0
(-2815 5480);
DISPLAY 0.787234 (-2815 5480);
PAINT MONO (-2815 5480);
FORCEPROP 1 LASTPIN (-2825 5300) $PN 2
J 0
(-2815 5280);
DISPLAY 0.787234 (-2815 5280);
PAINT MONO (-2815 5280);
FORCEPROP 1 LAST VOLTAGE 6.3V
J 0
(-2775 5400);
DISPLAY 0.510638 (-2775 5400);
FORCEPROP 1 LAST TOLERANCE 20%
J 0
(-2775 5350);
DISPLAY 0.510638 (-2775 5350);
FORCEPROP 1 LAST VALUE 10UF
J 0
(-2775 5450);
DISPLAY 0.510638 (-2775 5450);
FORCEPROP 1 LAST MATERIAL X6S
J 0
(-2775 5300);
DISPLAY 0.510638 (-2775 5300);
FORCEPROP 1 LAST PACK_TYPE C0402
J 0
(-2775 5250);
DISPLAY 0.510638 (-2775 5250);
FORCEPROP 2 LAST CDS_LIB pure_quanta
J 0
(-2825 5400);
DISPLAY INVISIBLE (-2825 5400);
FORCEPROP 1 LAST PATH I72
J 0
(-2775 5550);
DISPLAY 0.978723 (-2775 5550);
PAINT WHITE (-2775 5550);
DISPLAY INVISIBLE (-2775 5550);
FORCEPROP 1 LAST PART_NUMBER CH6101MEB01
J 0
(-2775 5250);
DISPLAY 0.978723 (-2775 5250);
DISPLAY INVISIBLE (-2775 5250);
FORCEADD Q_CAP..1
(-2525 5400);
FORCEPROP 1 LAST LOCATION C484
J 0
(-2475 5500);
DISPLAY 0.978723 (-2475 5500);
PAINT WHITE (-2475 5500);
FORCEPROP 0 LAST $SEC 1
J 0
(-2475 5550);
DISPLAY 0.680851 (-2475 5550);
PAINT MONO (-2475 5550);
DISPLAY INVISIBLE (-2475 5550);
FORCEPROP 0 LAST CDS_SEC 1
J 0
(-2475 5550);
DISPLAY 0.680851 (-2475 5550);
DISPLAY INVISIBLE (-2475 5550);
FORCEPROP 1 LASTPIN (-2525 5500) $PN 1
J 0
(-2515 5480);
DISPLAY 0.787234 (-2515 5480);
PAINT MONO (-2515 5480);
FORCEPROP 1 LASTPIN (-2525 5300) $PN 2
J 0
(-2515 5280);
DISPLAY 0.787234 (-2515 5280);
PAINT MONO (-2515 5280);
FORCEPROP 1 LAST VOLTAGE 6.3V
J 0
(-2475 5400);
DISPLAY 0.510638 (-2475 5400);
FORCEPROP 1 LAST PACK_TYPE 0402
J 0
(-2475 5250);
DISPLAY 0.510638 (-2475 5250);
FORCEPROP 1 LAST MATERIAL X6S
J 0
(-2475 5300);
DISPLAY 0.510638 (-2475 5300);
FORCEPROP 1 LAST TOLERANCE 20%
J 0
(-2475 5350);
DISPLAY 0.510638 (-2475 5350);
FORCEPROP 1 LAST VALUE 4.7UF
J 0
(-2475 5450);
DISPLAY 0.510638 (-2475 5450);
FORCEPROP 2 LAST CDS_LIB pure_quanta
J 0
(-2525 5400);
DISPLAY INVISIBLE (-2525 5400);
FORCEPROP 1 LAST PATH I73
J 0
(-2475 5550);
DISPLAY 0.978723 (-2475 5550);
PAINT WHITE (-2475 5550);
DISPLAY INVISIBLE (-2475 5550);
FORCEPROP 1 LAST PART_NUMBER CH5471MEB01
J 0
(-2475 5250);
DISPLAY 0.978723 (-2475 5250);
DISPLAY INVISIBLE (-2475 5250);
FORCEADD Q_CAP..1
(-2225 5400);
FORCEPROP 1 LAST LOCATION C454
J 0
(-2175 5500);
DISPLAY 0.978723 (-2175 5500);
PAINT WHITE (-2175 5500);
FORCEPROP 0 LAST $SEC 1
J 0
(-2175 5550);
DISPLAY 0.680851 (-2175 5550);
PAINT MONO (-2175 5550);
DISPLAY INVISIBLE (-2175 5550);
FORCEPROP 0 LAST CDS_SEC 1
J 0
(-2175 5550);
DISPLAY 0.680851 (-2175 5550);
DISPLAY INVISIBLE (-2175 5550);
FORCEPROP 1 LASTPIN (-2225 5500) $PN 1
J 0
(-2215 5480);
DISPLAY 0.787234 (-2215 5480);
PAINT MONO (-2215 5480);
FORCEPROP 1 LASTPIN (-2225 5300) $PN 2
J 0
(-2215 5280);
DISPLAY 0.787234 (-2215 5280);
PAINT MONO (-2215 5280);
FORCEPROP 1 LAST VALUE 1UF
J 0
(-2175 5450);
DISPLAY 0.510638 (-2175 5450);
FORCEPROP 1 LAST VOLTAGE 4V
J 0
(-2175 5400);
DISPLAY 0.510638 (-2175 5400);
FORCEPROP 1 LAST TOLERANCE 20%
J 0
(-2175 5350);
DISPLAY 0.510638 (-2175 5350);
FORCEPROP 1 LAST MATERIAL X6S
J 0
(-2175 5300);
DISPLAY 0.510638 (-2175 5300);
FORCEPROP 1 LAST PACK_TYPE 0201
J 0
(-2175 5250);
DISPLAY 0.510638 (-2175 5250);
FORCEPROP 2 LAST CDS_LIB pure_quanta
J 0
(-2225 5400);
DISPLAY INVISIBLE (-2225 5400);
FORCEPROP 1 LAST PATH I74
J 0
(-2175 5550);
DISPLAY 0.978723 (-2175 5550);
PAINT WHITE (-2175 5550);
DISPLAY INVISIBLE (-2175 5550);
FORCEPROP 1 LAST PART_NUMBER CH-10KMEE00
J 0
(-2175 5250);
DISPLAY 0.510638 (-2175 5250);
DISPLAY INVISIBLE (-2175 5250);
FORCEADD Q_CAP..1
(-1875 4150);
FORCEPROP 1 LAST LOCATION C487
J 0
(-1825 4250);
DISPLAY 0.978723 (-1825 4250);
PAINT WHITE (-1825 4250);
FORCEPROP 0 LAST $SEC 1
J 0
(-1825 4300);
DISPLAY 0.680851 (-1825 4300);
PAINT MONO (-1825 4300);
DISPLAY INVISIBLE (-1825 4300);
FORCEPROP 0 LAST CDS_SEC 1
J 0
(-1825 4300);
DISPLAY 0.680851 (-1825 4300);
DISPLAY INVISIBLE (-1825 4300);
FORCEPROP 1 LASTPIN (-1875 4250) $PN 1
J 0
(-1865 4230);
DISPLAY 0.787234 (-1865 4230);
PAINT MONO (-1865 4230);
FORCEPROP 1 LASTPIN (-1875 4050) $PN 2
J 0
(-1865 4030);
DISPLAY 0.787234 (-1865 4030);
PAINT MONO (-1865 4030);
FORCEPROP 1 LAST PACK_TYPE C0402
J 0
(-1825 4000);
DISPLAY 0.510638 (-1825 4000);
FORCEPROP 1 LAST MATERIAL X6S
J 0
(-1825 4050);
DISPLAY 0.510638 (-1825 4050);
FORCEPROP 1 LAST TOLERANCE 20%
J 0
(-1825 4100);
DISPLAY 0.510638 (-1825 4100);
FORCEPROP 1 LAST VALUE 22UF
J 0
(-1825 4200);
DISPLAY 0.510638 (-1825 4200);
FORCEPROP 1 LAST VOLTAGE 4V
J 0
(-1825 4150);
DISPLAY 0.510638 (-1825 4150);
FORCEPROP 2 LAST CDS_LIB pure_quanta
J 0
(-1875 4150);
DISPLAY INVISIBLE (-1875 4150);
FORCEPROP 1 LAST PATH I75
J 0
(-1825 4300);
DISPLAY 0.978723 (-1825 4300);
PAINT WHITE (-1825 4300);
DISPLAY INVISIBLE (-1825 4300);
FORCEPROP 1 LAST PART_NUMBER CH622KMEB02
J 0
(-1825 4000);
DISPLAY 0.978723 (-1825 4000);
DISPLAY INVISIBLE (-1825 4000);
FORCEADD Q_CAP..1
(-1575 4150);
FORCEPROP 1 LAST LOCATION C499
J 0
(-1525 4250);
DISPLAY 0.978723 (-1525 4250);
PAINT WHITE (-1525 4250);
FORCEPROP 0 LAST $SEC 1
J 0
(-1525 4300);
DISPLAY 0.680851 (-1525 4300);
PAINT MONO (-1525 4300);
DISPLAY INVISIBLE (-1525 4300);
FORCEPROP 0 LAST CDS_SEC 1
J 0
(-1525 4300);
DISPLAY 0.680851 (-1525 4300);
DISPLAY INVISIBLE (-1525 4300);
FORCEPROP 1 LASTPIN (-1575 4250) $PN 1
J 0
(-1565 4230);
DISPLAY 0.787234 (-1565 4230);
PAINT MONO (-1565 4230);
FORCEPROP 1 LASTPIN (-1575 4050) $PN 2
J 0
(-1565 4030);
DISPLAY 0.787234 (-1565 4030);
PAINT MONO (-1565 4030);
FORCEPROP 1 LAST VALUE 10UF
J 0
(-1525 4200);
DISPLAY 0.510638 (-1525 4200);
FORCEPROP 1 LAST VOLTAGE 6.3V
J 0
(-1525 4150);
DISPLAY 0.510638 (-1525 4150);
FORCEPROP 1 LAST TOLERANCE 20%
J 0
(-1525 4100);
DISPLAY 0.510638 (-1525 4100);
FORCEPROP 1 LAST MATERIAL X6S
J 0
(-1525 4050);
DISPLAY 0.510638 (-1525 4050);
FORCEPROP 1 LAST PACK_TYPE C0402
J 0
(-1525 4000);
DISPLAY 0.510638 (-1525 4000);
FORCEPROP 2 LAST CDS_LIB pure_quanta
J 0
(-1575 4150);
DISPLAY INVISIBLE (-1575 4150);
FORCEPROP 1 LAST PATH I76
J 0
(-1525 4300);
DISPLAY 0.978723 (-1525 4300);
PAINT WHITE (-1525 4300);
DISPLAY INVISIBLE (-1525 4300);
FORCEPROP 1 LAST PART_NUMBER CH6101MEB01
J 0
(-1525 4000);
DISPLAY 0.978723 (-1525 4000);
DISPLAY INVISIBLE (-1525 4000);
FORCEADD Q_CAP..1
(-1275 4150);
FORCEPROP 1 LAST LOCATION C482
J 0
(-1225 4250);
DISPLAY 0.978723 (-1225 4250);
PAINT WHITE (-1225 4250);
FORCEPROP 0 LAST $SEC 1
J 0
(-1225 4300);
DISPLAY 0.680851 (-1225 4300);
PAINT MONO (-1225 4300);
DISPLAY INVISIBLE (-1225 4300);
FORCEPROP 0 LAST CDS_SEC 1
J 0
(-1225 4300);
DISPLAY 0.680851 (-1225 4300);
DISPLAY INVISIBLE (-1225 4300);
FORCEPROP 1 LASTPIN (-1275 4250) $PN 1
J 0
(-1265 4230);
DISPLAY 0.787234 (-1265 4230);
PAINT MONO (-1265 4230);
FORCEPROP 1 LASTPIN (-1275 4050) $PN 2
J 0
(-1265 4030);
DISPLAY 0.787234 (-1265 4030);
PAINT MONO (-1265 4030);
FORCEPROP 1 LAST PACK_TYPE C0402
J 0
(-1225 4000);
DISPLAY 0.510638 (-1225 4000);
FORCEPROP 1 LAST MATERIAL X6S
J 0
(-1225 4050);
DISPLAY 0.510638 (-1225 4050);
FORCEPROP 1 LAST TOLERANCE 20%
J 0
(-1225 4100);
DISPLAY 0.510638 (-1225 4100);
FORCEPROP 1 LAST VALUE 10UF
J 0
(-1225 4200);
DISPLAY 0.510638 (-1225 4200);
FORCEPROP 1 LAST VOLTAGE 6.3V
J 0
(-1225 4150);
DISPLAY 0.510638 (-1225 4150);
FORCEPROP 2 LAST CDS_LIB pure_quanta
J 0
(-1275 4150);
DISPLAY INVISIBLE (-1275 4150);
FORCEPROP 1 LAST PATH I77
J 0
(-1225 4300);
DISPLAY 0.978723 (-1225 4300);
PAINT WHITE (-1225 4300);
DISPLAY INVISIBLE (-1225 4300);
FORCEPROP 1 LAST PART_NUMBER CH6101MEB01
J 0
(-1225 4000);
DISPLAY 0.978723 (-1225 4000);
DISPLAY INVISIBLE (-1225 4000);
FORCEADD Q_CAP..1
(-1925 5375);
FORCEPROP 1 LAST LOCATION C449
J 0
(-1875 5475);
DISPLAY 0.978723 (-1875 5475);
PAINT WHITE (-1875 5475);
FORCEPROP 0 LAST $SEC 1
J 0
(-1875 5525);
DISPLAY 0.680851 (-1875 5525);
PAINT MONO (-1875 5525);
DISPLAY INVISIBLE (-1875 5525);
FORCEPROP 0 LAST CDS_SEC 1
J 0
(-1875 5525);
DISPLAY 0.680851 (-1875 5525);
DISPLAY INVISIBLE (-1875 5525);
FORCEPROP 1 LASTPIN (-1925 5475) $PN 1
J 0
(-1915 5455);
DISPLAY 0.787234 (-1915 5455);
PAINT MONO (-1915 5455);
FORCEPROP 1 LASTPIN (-1925 5275) $PN 2
J 0
(-1915 5255);
DISPLAY 0.787234 (-1915 5255);
PAINT MONO (-1915 5255);
FORCEPROP 1 LAST VOLTAGE 10V
J 0
(-1875 5375);
DISPLAY 0.638298 (-1875 5375);
FORCEPROP 1 LAST VALUE 0.1UF
J 0
(-1875 5425);
DISPLAY 0.638298 (-1875 5425);
FORCEPROP 1 LAST PACK_TYPE C0201
J 0
(-1875 5225);
DISPLAY 0.638298 (-1875 5225);
FORCEPROP 1 LAST MATERIAL X7S
J 0
(-1875 5275);
DISPLAY 0.638298 (-1875 5275);
FORCEPROP 1 LAST TOLERANCE 10%
J 0
(-1875 5325);
DISPLAY 0.638298 (-1875 5325);
FORCEPROP 2 LAST CDS_LIB pure_quanta
J 0
(-1925 5375);
DISPLAY INVISIBLE (-1925 5375);
FORCEPROP 1 LAST PATH I78
J 0
(-1875 5525);
DISPLAY 0.978723 (-1875 5525);
PAINT WHITE (-1875 5525);
DISPLAY INVISIBLE (-1875 5525);
FORCEPROP 1 LAST PART_NUMBER CH4102K6E00
J 0
(-1875 5225);
DISPLAY 0.978723 (-1875 5225);
DISPLAY INVISIBLE (-1875 5225);
FORCEADD Q_CAP..1
(-1650 5375);
FORCEPROP 1 LAST LOCATION C451
J 0
(-1600 5475);
DISPLAY 0.978723 (-1600 5475);
PAINT WHITE (-1600 5475);
FORCEPROP 0 LAST $SEC 1
J 0
(-1600 5525);
DISPLAY 0.680851 (-1600 5525);
PAINT MONO (-1600 5525);
DISPLAY INVISIBLE (-1600 5525);
FORCEPROP 0 LAST CDS_SEC 1
J 0
(-1600 5525);
DISPLAY 0.680851 (-1600 5525);
DISPLAY INVISIBLE (-1600 5525);
FORCEPROP 1 LASTPIN (-1650 5475) $PN 1
J 0
(-1640 5455);
DISPLAY 0.787234 (-1640 5455);
PAINT MONO (-1640 5455);
FORCEPROP 1 LASTPIN (-1650 5275) $PN 2
J 0
(-1640 5255);
DISPLAY 0.787234 (-1640 5255);
PAINT MONO (-1640 5255);
FORCEPROP 1 LAST TOLERANCE 10%
J 0
(-1600 5325);
DISPLAY 0.638298 (-1600 5325);
FORCEPROP 1 LAST PACK_TYPE C0201
J 0
(-1600 5225);
DISPLAY 0.638298 (-1600 5225);
FORCEPROP 1 LAST MATERIAL X7S
J 0
(-1600 5275);
DISPLAY 0.638298 (-1600 5275);
FORCEPROP 1 LAST VOLTAGE 10V
J 0
(-1600 5375);
DISPLAY 0.638298 (-1600 5375);
FORCEPROP 1 LAST VALUE 0.1UF
J 0
(-1600 5425);
DISPLAY 0.638298 (-1600 5425);
FORCEPROP 2 LAST CDS_LIB pure_quanta
J 0
(-1650 5375);
DISPLAY INVISIBLE (-1650 5375);
FORCEPROP 1 LAST PATH I79
J 0
(-1600 5525);
DISPLAY 0.978723 (-1600 5525);
PAINT WHITE (-1600 5525);
DISPLAY INVISIBLE (-1600 5525);
FORCEPROP 1 LAST PART_NUMBER CH4102K6E00
J 0
(-1600 5225);
DISPLAY 0.978723 (-1600 5225);
DISPLAY INVISIBLE (-1600 5225);
FORCEADD Q_RES..2
R 2
(-4300 2725);
FORCEPROP 1 LAST LOCATION R898
J 2
(-4345 2850);
DISPLAY 0.978723 (-4345 2850);
FORCEPROP 0 LAST $SEC 1
J 0
(-4325 2900);
DISPLAY 0.680851 (-4325 2900);
PAINT MONO (-4325 2900);
DISPLAY INVISIBLE (-4325 2900);
FORCEPROP 0 LAST CDS_SEC 1
J 0
(-4325 2900);
DISPLAY 0.680851 (-4325 2900);
DISPLAY INVISIBLE (-4325 2900);
FORCEPROP 1 LASTPIN (-4300 2825) $PN 1
J 2
(-4305 2787);
DISPLAY 0.787234 (-4305 2787);
PAINT MONO (-4305 2787);
FORCEPROP 1 LASTPIN (-4300 2625) $PN 2
J 2
(-4305 2635);
DISPLAY 0.787234 (-4305 2635);
PAINT MONO (-4305 2635);
FORCEPROP 1 LAST WATTAGE 1/4W
J 2
(-4340 2700);
DISPLAY 0.978723 (-4340 2700);
FORCEPROP 1 LAST MATERIAL EMPTY
J 2
(-4340 2650);
DISPLAY 0.978723 (-4340 2650);
FORCEPROP 1 LAST PACK_TYPE 0603LF
J 2
(-4340 2550);
DISPLAY 0.978723 (-4340 2550);
FORCEPROP 1 LAST VALUE 0
J 2
(-4345 2800);
DISPLAY 0.978723 (-4345 2800);
FORCEPROP 1 LAST TOLERANCE 5%
J 2
(-4345 2750);
DISPLAY 0.978723 (-4345 2750);
FORCEPROP 2 LAST CDS_LIB pure_quanta
J 2
(-4300 2725);
DISPLAY INVISIBLE (-4300 2725);
FORCEPROP 1 LAST PATH I8
J 2
(-4350 2900);
DISPLAY 0.978723 (-4350 2900);
PAINT WHITE (-4350 2900);
DISPLAY INVISIBLE (-4350 2900);
FORCEPROP 1 LAST PART_NUMBER CS00006J900
J 2
(-4340 2600);
DISPLAY 0.978723 (-4340 2600);
DISPLAY INVISIBLE (-4340 2600);
FORCEADD Q_CAP..1
(-1400 5375);
FORCEPROP 1 LAST LOCATION C493
J 0
(-1350 5475);
DISPLAY 0.978723 (-1350 5475);
PAINT WHITE (-1350 5475);
FORCEPROP 0 LAST $SEC 1
J 0
(-1350 5525);
DISPLAY 0.680851 (-1350 5525);
PAINT MONO (-1350 5525);
DISPLAY INVISIBLE (-1350 5525);
FORCEPROP 0 LAST CDS_SEC 1
J 0
(-1350 5525);
DISPLAY 0.680851 (-1350 5525);
DISPLAY INVISIBLE (-1350 5525);
FORCEPROP 1 LASTPIN (-1400 5475) $PN 1
J 0
(-1390 5455);
DISPLAY 0.787234 (-1390 5455);
PAINT MONO (-1390 5455);
FORCEPROP 1 LASTPIN (-1400 5275) $PN 2
J 0
(-1390 5255);
DISPLAY 0.787234 (-1390 5255);
PAINT MONO (-1390 5255);
FORCEPROP 1 LAST PACK_TYPE C0201
J 0
(-1350 5225);
DISPLAY 0.638298 (-1350 5225);
FORCEPROP 1 LAST MATERIAL X7S
J 0
(-1350 5275);
DISPLAY 0.638298 (-1350 5275);
FORCEPROP 1 LAST TOLERANCE 10%
J 0
(-1350 5325);
DISPLAY 0.638298 (-1350 5325);
FORCEPROP 1 LAST VOLTAGE 10V
J 0
(-1350 5375);
DISPLAY 0.638298 (-1350 5375);
FORCEPROP 1 LAST VALUE 0.1UF
J 0
(-1350 5425);
DISPLAY 0.638298 (-1350 5425);
FORCEPROP 2 LAST CDS_LIB pure_quanta
J 0
(-1400 5375);
DISPLAY INVISIBLE (-1400 5375);
FORCEPROP 1 LAST PATH I80
J 0
(-1350 5525);
DISPLAY 0.978723 (-1350 5525);
PAINT WHITE (-1350 5525);
DISPLAY INVISIBLE (-1350 5525);
FORCEPROP 1 LAST PART_NUMBER CH4102K6E00
J 0
(-1350 5225);
DISPLAY 0.978723 (-1350 5225);
DISPLAY INVISIBLE (-1350 5225);
FORCEADD UNIVERSAL_GND..1
(-1200 4975);
FORCEPROP 3 LASTPIN (-1200 5025) SIG_NAME GND\g
J 0
(-1190 5035);
DISPLAY 0.659574 (-1190 5035);
PAINT MONO (-1190 5035);
DISPLAY INVISIBLE (-1190 5035);
FORCEPROP 2 LAST CDS_LIB pure_quanta_power
J 0
(-1200 4975);
DISPLAY INVISIBLE (-1200 4975);
FORCEPROP 1 LAST HDL_POWER GND
J 1
(-1175 4900);
DISPLAY 0.872340 (-1175 4900);
PAINT GREEN (-1175 4900);
DISPLAY INVISIBLE (-1175 4900);
FORCEPROP 1 LAST PATH I81
J 0
(-1125 4975);
DISPLAY 0.872340 (-1125 4975);
PAINT AQUA (-1125 4975);
DISPLAY INVISIBLE (-1125 4975);
FORCEADD Q_CAP..1
(-1125 5375);
FORCEPROP 1 LAST LOCATION C458
J 0
(-1075 5475);
DISPLAY 0.978723 (-1075 5475);
PAINT WHITE (-1075 5475);
FORCEPROP 0 LAST $SEC 1
J 0
(-1075 5525);
DISPLAY 0.680851 (-1075 5525);
PAINT MONO (-1075 5525);
DISPLAY INVISIBLE (-1075 5525);
FORCEPROP 0 LAST CDS_SEC 1
J 0
(-1075 5525);
DISPLAY 0.680851 (-1075 5525);
DISPLAY INVISIBLE (-1075 5525);
FORCEPROP 1 LASTPIN (-1125 5475) $PN 1
J 0
(-1115 5455);
DISPLAY 0.787234 (-1115 5455);
PAINT MONO (-1115 5455);
FORCEPROP 1 LASTPIN (-1125 5275) $PN 2
J 0
(-1115 5255);
DISPLAY 0.787234 (-1115 5255);
PAINT MONO (-1115 5255);
FORCEPROP 1 LAST PACK_TYPE C0201
J 0
(-1075 5225);
DISPLAY 0.638298 (-1075 5225);
FORCEPROP 1 LAST MATERIAL X7S
J 0
(-1075 5275);
DISPLAY 0.638298 (-1075 5275);
FORCEPROP 1 LAST TOLERANCE 10%
J 0
(-1075 5325);
DISPLAY 0.638298 (-1075 5325);
FORCEPROP 1 LAST VOLTAGE 10V
J 0
(-1075 5375);
DISPLAY 0.638298 (-1075 5375);
FORCEPROP 1 LAST VALUE 0.1UF
J 0
(-1075 5425);
DISPLAY 0.638298 (-1075 5425);
FORCEPROP 2 LAST CDS_LIB pure_quanta
J 0
(-1125 5375);
DISPLAY INVISIBLE (-1125 5375);
FORCEPROP 1 LAST PATH I82
J 0
(-1075 5525);
DISPLAY 0.978723 (-1075 5525);
PAINT WHITE (-1075 5525);
DISPLAY INVISIBLE (-1075 5525);
FORCEPROP 1 LAST PART_NUMBER CH4102K6E00
J 0
(-1075 5225);
DISPLAY 0.978723 (-1075 5225);
DISPLAY INVISIBLE (-1075 5225);
FORCEADD Q_CAP..1
(-1375 2200);
FORCEPROP 1 LAST LOCATION C462
J 0
(-1325 2300);
DISPLAY 0.978723 (-1325 2300);
PAINT WHITE (-1325 2300);
FORCEPROP 0 LAST $SEC 1
J 0
(-1325 2350);
DISPLAY 0.680851 (-1325 2350);
PAINT MONO (-1325 2350);
DISPLAY INVISIBLE (-1325 2350);
FORCEPROP 0 LAST CDS_SEC 1
J 0
(-1325 2350);
DISPLAY 0.680851 (-1325 2350);
DISPLAY INVISIBLE (-1325 2350);
FORCEPROP 1 LASTPIN (-1375 2300) $PN 1
J 0
(-1365 2280);
DISPLAY 0.787234 (-1365 2280);
PAINT MONO (-1365 2280);
FORCEPROP 1 LASTPIN (-1375 2100) $PN 2
J 0
(-1365 2080);
DISPLAY 0.787234 (-1365 2080);
PAINT MONO (-1365 2080);
FORCEPROP 1 LAST PACK_TYPE C0201
J 0
(-1325 2050);
DISPLAY 0.638298 (-1325 2050);
FORCEPROP 1 LAST VALUE 0.1UF
J 0
(-1325 2250);
DISPLAY 0.638298 (-1325 2250);
FORCEPROP 1 LAST MATERIAL X7S
J 0
(-1325 2100);
DISPLAY 0.638298 (-1325 2100);
FORCEPROP 1 LAST VOLTAGE 10V
J 0
(-1325 2200);
DISPLAY 0.638298 (-1325 2200);
FORCEPROP 1 LAST TOLERANCE 10%
J 0
(-1325 2150);
DISPLAY 0.638298 (-1325 2150);
FORCEPROP 2 LAST CDS_LIB pure_quanta
J 0
(-1375 2200);
DISPLAY INVISIBLE (-1375 2200);
FORCEPROP 1 LAST PATH I83
J 0
(-1325 2350);
DISPLAY 0.978723 (-1325 2350);
PAINT WHITE (-1325 2350);
DISPLAY INVISIBLE (-1325 2350);
FORCEPROP 1 LAST PART_NUMBER CH4102K6E00
J 0
(-1325 2050);
DISPLAY 0.978723 (-1325 2050);
DISPLAY INVISIBLE (-1325 2050);
FORCEADD Q_CAP..1
(-1875 3525);
FORCEPROP 1 LAST LOCATION C452
J 0
(-1825 3625);
DISPLAY 0.978723 (-1825 3625);
PAINT WHITE (-1825 3625);
FORCEPROP 0 LAST $SEC 1
J 0
(-1825 3675);
DISPLAY 0.680851 (-1825 3675);
PAINT MONO (-1825 3675);
DISPLAY INVISIBLE (-1825 3675);
FORCEPROP 0 LAST CDS_SEC 1
J 0
(-1825 3675);
DISPLAY 0.680851 (-1825 3675);
DISPLAY INVISIBLE (-1825 3675);
FORCEPROP 1 LASTPIN (-1875 3625) $PN 1
J 0
(-1865 3605);
DISPLAY 0.787234 (-1865 3605);
PAINT MONO (-1865 3605);
FORCEPROP 1 LASTPIN (-1875 3425) $PN 2
J 0
(-1865 3405);
DISPLAY 0.787234 (-1865 3405);
PAINT MONO (-1865 3405);
FORCEPROP 1 LAST PACK_TYPE 0201
J 0
(-1825 3375);
DISPLAY 0.510638 (-1825 3375);
FORCEPROP 1 LAST VALUE 1UF
J 0
(-1825 3575);
DISPLAY 0.510638 (-1825 3575);
FORCEPROP 1 LAST TOLERANCE 20%
J 0
(-1825 3475);
DISPLAY 0.510638 (-1825 3475);
FORCEPROP 1 LAST MATERIAL X6S
J 0
(-1825 3425);
DISPLAY 0.510638 (-1825 3425);
FORCEPROP 1 LAST VOLTAGE 4V
J 0
(-1825 3525);
DISPLAY 0.510638 (-1825 3525);
FORCEPROP 2 LAST CDS_LIB pure_quanta
J 0
(-1875 3525);
DISPLAY INVISIBLE (-1875 3525);
FORCEPROP 1 LAST PATH I84
J 0
(-1825 3675);
DISPLAY 0.978723 (-1825 3675);
PAINT WHITE (-1825 3675);
DISPLAY INVISIBLE (-1825 3675);
FORCEPROP 1 LAST PART_NUMBER CH-10KMEE00
J 0
(-1825 3375);
DISPLAY 0.510638 (-1825 3375);
DISPLAY INVISIBLE (-1825 3375);
FORCEADD Q_CAP..1
(-2325 4150);
FORCEPROP 1 LAST LOCATION C486
J 0
(-2275 4250);
DISPLAY 0.978723 (-2275 4250);
PAINT WHITE (-2275 4250);
FORCEPROP 0 LAST $SEC 1
J 0
(-2275 4300);
DISPLAY 0.680851 (-2275 4300);
PAINT MONO (-2275 4300);
DISPLAY INVISIBLE (-2275 4300);
FORCEPROP 0 LAST CDS_SEC 1
J 0
(-2275 4300);
DISPLAY 0.680851 (-2275 4300);
DISPLAY INVISIBLE (-2275 4300);
FORCEPROP 1 LASTPIN (-2325 4250) $PN 1
J 0
(-2315 4230);
DISPLAY 0.787234 (-2315 4230);
PAINT MONO (-2315 4230);
FORCEPROP 1 LASTPIN (-2325 4050) $PN 2
J 0
(-2315 4030);
DISPLAY 0.787234 (-2315 4030);
PAINT MONO (-2315 4030);
FORCEPROP 1 LAST TOLERANCE 20%
J 0
(-2275 4100);
DISPLAY 0.510638 (-2275 4100);
FORCEPROP 1 LAST MATERIAL X6S
J 0
(-2275 4050);
DISPLAY 0.510638 (-2275 4050);
FORCEPROP 1 LAST VOLTAGE 4V
J 0
(-2275 4150);
DISPLAY 0.510638 (-2275 4150);
FORCEPROP 1 LAST VALUE 22UF
J 0
(-2275 4200);
DISPLAY 0.510638 (-2275 4200);
FORCEPROP 1 LAST PACK_TYPE C0402
J 0
(-2275 4000);
DISPLAY 0.510638 (-2275 4000);
FORCEPROP 2 LAST CDS_LIB pure_quanta
J 0
(-2325 4150);
DISPLAY INVISIBLE (-2325 4150);
FORCEPROP 1 LAST PATH I85
J 0
(-2275 4300);
DISPLAY 0.978723 (-2275 4300);
PAINT WHITE (-2275 4300);
DISPLAY INVISIBLE (-2275 4300);
FORCEPROP 1 LAST PART_NUMBER CH622KMEB02
J 0
(-2275 4000);
DISPLAY 0.978723 (-2275 4000);
DISPLAY INVISIBLE (-2275 4000);
FORCEADD Q_CAP..1
(-2550 3525);
FORCEPROP 1 LAST LOCATION C483
J 0
(-2500 3625);
DISPLAY 0.978723 (-2500 3625);
PAINT WHITE (-2500 3625);
FORCEPROP 0 LAST $SEC 1
J 0
(-2500 3675);
DISPLAY 0.680851 (-2500 3675);
PAINT MONO (-2500 3675);
DISPLAY INVISIBLE (-2500 3675);
FORCEPROP 0 LAST CDS_SEC 1
J 0
(-2500 3675);
DISPLAY 0.680851 (-2500 3675);
DISPLAY INVISIBLE (-2500 3675);
FORCEPROP 1 LASTPIN (-2550 3625) $PN 1
J 0
(-2540 3605);
DISPLAY 0.787234 (-2540 3605);
PAINT MONO (-2540 3605);
FORCEPROP 1 LASTPIN (-2550 3425) $PN 2
J 0
(-2540 3405);
DISPLAY 0.787234 (-2540 3405);
PAINT MONO (-2540 3405);
FORCEPROP 1 LAST MATERIAL X6S
J 0
(-2500 3425);
DISPLAY 0.510638 (-2500 3425);
FORCEPROP 1 LAST TOLERANCE 20%
J 0
(-2500 3475);
DISPLAY 0.510638 (-2500 3475);
FORCEPROP 1 LAST VOLTAGE 6.3V
J 0
(-2500 3525);
DISPLAY 0.510638 (-2500 3525);
FORCEPROP 1 LAST PACK_TYPE 0402
J 0
(-2500 3375);
DISPLAY 0.510638 (-2500 3375);
FORCEPROP 1 LAST VALUE 4.7UF
J 0
(-2500 3575);
DISPLAY 0.510638 (-2500 3575);
FORCEPROP 2 LAST CDS_LIB pure_quanta
J 0
(-2550 3525);
DISPLAY INVISIBLE (-2550 3525);
FORCEPROP 1 LAST PATH I86
J 0
(-2500 3675);
DISPLAY 0.978723 (-2500 3675);
PAINT WHITE (-2500 3675);
DISPLAY INVISIBLE (-2500 3675);
FORCEPROP 1 LAST PART_NUMBER CH5471MEB01
J 0
(-2500 3375);
DISPLAY 0.978723 (-2500 3375);
DISPLAY INVISIBLE (-2500 3375);
FORCEADD Q_CAP..1
(-2800 4150);
FORCEPROP 1 LAST LOCATION C479
J 0
(-2750 4250);
DISPLAY 0.978723 (-2750 4250);
PAINT WHITE (-2750 4250);
FORCEPROP 0 LAST $SEC 1
J 0
(-2750 4300);
DISPLAY 0.680851 (-2750 4300);
PAINT MONO (-2750 4300);
DISPLAY INVISIBLE (-2750 4300);
FORCEPROP 0 LAST CDS_SEC 1
J 0
(-2750 4300);
DISPLAY 0.680851 (-2750 4300);
DISPLAY INVISIBLE (-2750 4300);
FORCEPROP 1 LASTPIN (-2800 4250) $PN 1
J 0
(-2790 4230);
DISPLAY 0.787234 (-2790 4230);
PAINT MONO (-2790 4230);
FORCEPROP 1 LASTPIN (-2800 4050) $PN 2
J 0
(-2790 4030);
DISPLAY 0.787234 (-2790 4030);
PAINT MONO (-2790 4030);
FORCEPROP 1 LAST PACK_TYPE C0805
J 0
(-2750 4000);
DISPLAY 0.510638 (-2750 4000);
FORCEPROP 1 LAST TOLERANCE 20%
J 0
(-2750 4100);
DISPLAY 0.510638 (-2750 4100);
FORCEPROP 1 LAST VALUE 100UF
J 0
(-2750 4200);
DISPLAY 0.510638 (-2750 4200);
FORCEPROP 1 LAST VOLTAGE 4V
J 0
(-2750 4150);
DISPLAY 0.510638 (-2750 4150);
FORCEPROP 1 LAST MATERIAL X6S
J 0
(-2750 4050);
DISPLAY 0.510638 (-2750 4050);
FORCEPROP 2 LAST CDS_LIB pure_quanta
J 0
(-2800 4150);
DISPLAY INVISIBLE (-2800 4150);
FORCEPROP 1 LAST PATH I87
J 0
(-2750 4300);
DISPLAY 0.978723 (-2750 4300);
PAINT WHITE (-2750 4300);
DISPLAY INVISIBLE (-2750 4300);
FORCEPROP 1 LAST PART_NUMBER CH710KMEA01
J 0
(-2750 4000);
DISPLAY 0.404255 (-2750 4000);
DISPLAY INVISIBLE (-2750 4000);
FORCEADD Q_INDUCTOR..1
R 3
(-8225 4075);
FORCEPROP 1 LAST LOCATION L33
R 1
J 2
(-8385 4200);
DISPLAY 0.723404 (-8385 4200);
PAINT GREEN (-8385 4200);
FORCEPROP 0 LAST $SEC 1
R 1
J 0
(-8200 4200);
DISPLAY 0.680851 (-8200 4200);
PAINT MONO (-8200 4200);
DISPLAY INVISIBLE (-8200 4200);
FORCEPROP 0 LAST CDS_SEC 1
R 1
J 0
(-8200 4200);
DISPLAY 0.680851 (-8200 4200);
DISPLAY INVISIBLE (-8200 4200);
FORCEPROP 0 LASTPIN (-8200 4175) $PN 1
R 1
J 0
(-8210 4185);
DISPLAY 0.680851 (-8210 4185);
PAINT MONO (-8210 4185);
FORCEPROP 0 LASTPIN (-8200 3975) $PN 2
R 1
J 2
(-8210 3965);
DISPLAY 0.680851 (-8210 3965);
PAINT MONO (-8210 3965);
FORCEPROP 1 LAST MATERIAL IND
R 1
J 2
(-8280 4200);
DISPLAY 0.574468 (-8280 4200);
PAINT GREEN (-8280 4200);
FORCEPROP 2 LAST VALUE BLM15PD121SN1D/1300MA
R 1
J 2
(-8475 4200);
DISPLAY 0.553191 (-8475 4200);
FORCEPROP 2 LAST PACK_TYPE SMLF
R 1
J 2
(-8425 4200);
DISPLAY 0.553191 (-8425 4200);
FORCEPROP 1 LAST NEEDS_NO_SIZE TRUE
R 1
J 2
(-8225 4075);
DISPLAY 0.468085 (-8225 4075);
PAINT GREEN (-8225 4075);
DISPLAY INVISIBLE (-8225 4075);
FORCEPROP 2 LAST CDS_LIB pure_quanta
J 0
(-8225 4075);
DISPLAY INVISIBLE (-8225 4075);
FORCEPROP 1 LAST PATH I88
R 1
J 2
(-8280 4000);
DISPLAY 0.723404 (-8280 4000);
PAINT GREEN (-8280 4000);
DISPLAY INVISIBLE (-8280 4000);
FORCEPROP 1 LAST PART_NUMBER CX5PD121000
R 1
J 2
(-8325 4200);
DISPLAY 0.574468 (-8325 4200);
PAINT GREEN (-8325 4200);
DISPLAY INVISIBLE (-8325 4200);
FORCEADD Q_RES..2
(-8100 4050);
FORCEPROP 1 LAST LOCATION R897
J 0
(-8055 4175);
DISPLAY 0.808511 (-8055 4175);
FORCEPROP 0 LAST $SEC 1
J 0
(-8050 4225);
DISPLAY 0.680851 (-8050 4225);
PAINT MONO (-8050 4225);
DISPLAY INVISIBLE (-8050 4225);
FORCEPROP 0 LAST CDS_SEC 1
J 0
(-8050 4225);
DISPLAY 0.680851 (-8050 4225);
DISPLAY INVISIBLE (-8050 4225);
FORCEPROP 1 LASTPIN (-8100 4150) $PN 1
J 0
(-8095 4112);
DISPLAY 0.787234 (-8095 4112);
PAINT MONO (-8095 4112);
FORCEPROP 1 LASTPIN (-8100 3950) $PN 2
J 0
(-8095 3960);
DISPLAY 0.787234 (-8095 3960);
PAINT MONO (-8095 3960);
FORCEPROP 1 LAST VALUE 0
J 0
(-8055 4125);
DISPLAY 0.638298 (-8055 4125);
FORCEPROP 1 LAST WATTAGE 1/16W
J 0
(-8060 4025);
DISPLAY 0.638298 (-8060 4025);
FORCEPROP 1 LAST TOLERANCE 5%
J 0
(-8055 4075);
DISPLAY 0.638298 (-8055 4075);
FORCEPROP 1 LAST PACK_TYPE 0402LF
J 0
(-8060 3875);
DISPLAY 0.638298 (-8060 3875);
FORCEPROP 1 LAST MATERIAL EMPTY
J 0
(-8060 3975);
DISPLAY 0.638298 (-8060 3975);
PAINT RED (-8060 3975);
FORCEPROP 2 LAST CDS_LIB pure_quanta
J 0
(-8100 4050);
DISPLAY INVISIBLE (-8100 4050);
FORCEPROP 1 LAST PATH I89
J 0
(-8050 4225);
DISPLAY 0.978723 (-8050 4225);
PAINT WHITE (-8050 4225);
DISPLAY INVISIBLE (-8050 4225);
FORCEPROP 1 LAST PART_NUMBER CS00002JB13
J 0
(-8060 3925);
DISPLAY 0.638298 (-8060 3925);
DISPLAY INVISIBLE (-8060 3925);
FORCEADD Q_CAP..1
(-3025 1100);
FORCEPROP 1 LAST LOCATION C456
J 0
(-2975 1200);
DISPLAY 0.978723 (-2975 1200);
PAINT WHITE (-2975 1200);
FORCEPROP 0 LAST $SEC 1
J 0
(-2975 1250);
DISPLAY 0.680851 (-2975 1250);
PAINT MONO (-2975 1250);
DISPLAY INVISIBLE (-2975 1250);
FORCEPROP 0 LAST CDS_SEC 1
J 0
(-2975 1250);
DISPLAY 0.680851 (-2975 1250);
DISPLAY INVISIBLE (-2975 1250);
FORCEPROP 1 LASTPIN (-3025 1200) $PN 1
J 0
(-3015 1180);
DISPLAY 0.787234 (-3015 1180);
PAINT MONO (-3015 1180);
FORCEPROP 1 LASTPIN (-3025 1000) $PN 2
J 0
(-3015 980);
DISPLAY 0.787234 (-3015 980);
PAINT MONO (-3015 980);
FORCEPROP 1 LAST PACK_TYPE 0201
J 0
(-2975 950);
DISPLAY 0.510638 (-2975 950);
FORCEPROP 1 LAST MATERIAL X6S
J 0
(-2975 1000);
DISPLAY 0.510638 (-2975 1000);
FORCEPROP 1 LAST TOLERANCE 20%
J 0
(-2975 1050);
DISPLAY 0.510638 (-2975 1050);
FORCEPROP 1 LAST VALUE 1UF
J 0
(-2975 1150);
DISPLAY 0.510638 (-2975 1150);
FORCEPROP 1 LAST VOLTAGE 4V
J 0
(-2975 1100);
DISPLAY 0.510638 (-2975 1100);
FORCEPROP 2 LAST CDS_LIB pure_quanta
J 0
(-3025 1100);
DISPLAY INVISIBLE (-3025 1100);
FORCEPROP 1 LAST PATH I90
J 0
(-2975 1250);
DISPLAY 0.978723 (-2975 1250);
PAINT WHITE (-2975 1250);
DISPLAY INVISIBLE (-2975 1250);
FORCEPROP 1 LAST PART_NUMBER CH-10KMEE00
J 0
(-2975 950);
DISPLAY 0.510638 (-2975 950);
DISPLAY INVISIBLE (-2975 950);
FORCEADD Q_CAP..1
(-2775 1100);
FORCEPROP 1 LAST LOCATION C460
J 0
(-2725 1200);
DISPLAY 0.978723 (-2725 1200);
PAINT WHITE (-2725 1200);
FORCEPROP 0 LAST $SEC 1
J 0
(-2725 1250);
DISPLAY 0.680851 (-2725 1250);
PAINT MONO (-2725 1250);
DISPLAY INVISIBLE (-2725 1250);
FORCEPROP 0 LAST CDS_SEC 1
J 0
(-2725 1250);
DISPLAY 0.680851 (-2725 1250);
DISPLAY INVISIBLE (-2725 1250);
FORCEPROP 1 LASTPIN (-2775 1200) $PN 1
J 0
(-2765 1180);
DISPLAY 0.787234 (-2765 1180);
PAINT MONO (-2765 1180);
FORCEPROP 1 LASTPIN (-2775 1000) $PN 2
J 0
(-2765 980);
DISPLAY 0.787234 (-2765 980);
PAINT MONO (-2765 980);
FORCEPROP 1 LAST VALUE 1UF
J 0
(-2725 1150);
DISPLAY 0.510638 (-2725 1150);
FORCEPROP 1 LAST TOLERANCE 20%
J 0
(-2725 1050);
DISPLAY 0.510638 (-2725 1050);
FORCEPROP 1 LAST MATERIAL X6S
J 0
(-2725 1000);
DISPLAY 0.510638 (-2725 1000);
FORCEPROP 1 LAST PACK_TYPE 0201
J 0
(-2725 950);
DISPLAY 0.510638 (-2725 950);
FORCEPROP 1 LAST VOLTAGE 4V
J 0
(-2725 1100);
DISPLAY 0.510638 (-2725 1100);
FORCEPROP 2 LAST CDS_LIB pure_quanta
J 0
(-2775 1100);
DISPLAY INVISIBLE (-2775 1100);
FORCEPROP 1 LAST PATH I91
J 0
(-2725 1250);
DISPLAY 0.978723 (-2725 1250);
PAINT WHITE (-2725 1250);
DISPLAY INVISIBLE (-2725 1250);
FORCEPROP 1 LAST PART_NUMBER CH-10KMEE00
J 0
(-2725 950);
DISPLAY 0.510638 (-2725 950);
DISPLAY INVISIBLE (-2725 950);
FORCEADD Q_CAP..1
(-1850 2875);
FORCEPROP 1 LAST LOCATION C496
J 0
(-1800 2975);
DISPLAY 0.978723 (-1800 2975);
PAINT WHITE (-1800 2975);
FORCEPROP 0 LAST $SEC 1
J 0
(-1800 3025);
DISPLAY 0.680851 (-1800 3025);
PAINT MONO (-1800 3025);
DISPLAY INVISIBLE (-1800 3025);
FORCEPROP 0 LAST CDS_SEC 1
J 0
(-1800 3025);
DISPLAY 0.680851 (-1800 3025);
DISPLAY INVISIBLE (-1800 3025);
FORCEPROP 1 LASTPIN (-1850 2975) $PN 1
J 0
(-1840 2955);
DISPLAY 0.787234 (-1840 2955);
PAINT MONO (-1840 2955);
FORCEPROP 1 LASTPIN (-1850 2775) $PN 2
J 0
(-1840 2755);
DISPLAY 0.787234 (-1840 2755);
PAINT MONO (-1840 2755);
FORCEPROP 1 LAST PACK_TYPE C0201
J 0
(-1800 2725);
DISPLAY 0.638298 (-1800 2725);
FORCEPROP 1 LAST TOLERANCE 10%
J 0
(-1800 2825);
DISPLAY 0.638298 (-1800 2825);
FORCEPROP 1 LAST VALUE 0.1UF
J 0
(-1800 2925);
DISPLAY 0.638298 (-1800 2925);
FORCEPROP 1 LAST VOLTAGE 10V
J 0
(-1800 2875);
DISPLAY 0.638298 (-1800 2875);
FORCEPROP 1 LAST MATERIAL X7S
J 0
(-1800 2775);
DISPLAY 0.638298 (-1800 2775);
FORCEPROP 2 LAST CDS_LIB pure_quanta
J 0
(-1850 2875);
DISPLAY INVISIBLE (-1850 2875);
FORCEPROP 1 LAST PATH I92
J 0
(-1800 3025);
DISPLAY 0.978723 (-1800 3025);
PAINT WHITE (-1800 3025);
DISPLAY INVISIBLE (-1800 3025);
FORCEPROP 1 LAST PART_NUMBER CH4102K6E00
J 0
(-1800 2725);
DISPLAY 0.978723 (-1800 2725);
DISPLAY INVISIBLE (-1800 2725);
FORCEADD Q_CAP..1
(-1600 2875);
FORCEPROP 1 LAST LOCATION C498
J 0
(-1550 2975);
DISPLAY 0.978723 (-1550 2975);
PAINT WHITE (-1550 2975);
FORCEPROP 0 LAST $SEC 1
J 0
(-1550 3025);
DISPLAY 0.680851 (-1550 3025);
PAINT MONO (-1550 3025);
DISPLAY INVISIBLE (-1550 3025);
FORCEPROP 0 LAST CDS_SEC 1
J 0
(-1550 3025);
DISPLAY 0.680851 (-1550 3025);
DISPLAY INVISIBLE (-1550 3025);
FORCEPROP 1 LASTPIN (-1600 2975) $PN 1
J 0
(-1590 2955);
DISPLAY 0.787234 (-1590 2955);
PAINT MONO (-1590 2955);
FORCEPROP 1 LASTPIN (-1600 2775) $PN 2
J 0
(-1590 2755);
DISPLAY 0.787234 (-1590 2755);
PAINT MONO (-1590 2755);
FORCEPROP 1 LAST VALUE 0.1UF
J 0
(-1550 2925);
DISPLAY 0.638298 (-1550 2925);
FORCEPROP 1 LAST VOLTAGE 10V
J 0
(-1550 2875);
DISPLAY 0.638298 (-1550 2875);
FORCEPROP 1 LAST TOLERANCE 10%
J 0
(-1550 2825);
DISPLAY 0.638298 (-1550 2825);
FORCEPROP 1 LAST PACK_TYPE C0201
J 0
(-1550 2725);
DISPLAY 0.638298 (-1550 2725);
FORCEPROP 1 LAST MATERIAL X7S
J 0
(-1550 2775);
DISPLAY 0.638298 (-1550 2775);
FORCEPROP 2 LAST CDS_LIB pure_quanta
J 0
(-1600 2875);
DISPLAY INVISIBLE (-1600 2875);
FORCEPROP 1 LAST PATH I93
J 0
(-1550 3025);
DISPLAY 0.978723 (-1550 3025);
PAINT WHITE (-1550 3025);
DISPLAY INVISIBLE (-1550 3025);
FORCEPROP 1 LAST PART_NUMBER CH4102K6E00
J 0
(-1550 2725);
DISPLAY 0.978723 (-1550 2725);
DISPLAY INVISIBLE (-1550 2725);
FORCEADD Q_CAPP..1
(-1075 2225);
FORCEPROP 1 LAST LOCATION C7029
J 0
(-1025 2325);
DISPLAY 0.787234 (-1025 2325);
FORCEPROP 0 LAST $SEC 1
J 0
(-1025 2375);
DISPLAY 0.680851 (-1025 2375);
PAINT MONO (-1025 2375);
DISPLAY INVISIBLE (-1025 2375);
FORCEPROP 0 LAST CDS_SEC 1
J 0
(-1025 2375);
DISPLAY 0.680851 (-1025 2375);
DISPLAY INVISIBLE (-1025 2375);
FORCEPROP 1 LASTPIN (-1075 2325) $PN 1
J 0
(-1065 2310);
DISPLAY 0.787234 (-1065 2310);
PAINT MONO (-1065 2310);
FORCEPROP 1 LASTPIN (-1075 2125) $PN 2
J 0
(-1065 2110);
DISPLAY 0.787234 (-1065 2110);
PAINT MONO (-1065 2110);
FORCEPROP 1 LAST PACK_TYPE SMLF
J 0
(-1025 2075);
DISPLAY 0.510638 (-1025 2075);
FORCEPROP 1 LAST MATERIAL SPCAP
J 0
(-1025 2125);
DISPLAY 0.510638 (-1025 2125);
FORCEPROP 1 LAST VOLTAGE 2.5V
J 0
(-1025 2175);
DISPLAY 0.510638 (-1025 2175);
FORCEPROP 1 LAST VALUE 470UF
J 0
(-1025 2275);
DISPLAY 0.510638 (-1025 2275);
FORCEPROP 1 LAST TOLERANCE 20%
J 0
(-1025 2225);
DISPLAY 0.510638 (-1025 2225);
FORCEPROP 2 LAST CDS_LIB pure_quanta
J 0
(-1075 2225);
DISPLAY INVISIBLE (-1075 2225);
FORCEPROP 1 LAST PATH I94
J 0
(-1025 2375);
DISPLAY 0.978723 (-1025 2375);
DISPLAY INVISIBLE (-1025 2375);
FORCEPROP 1 LAST PART_NUMBER CH747LM8818
J 0
(-1025 2025);
DISPLAY 0.404255 (-1025 2025);
DISPLAY INVISIBLE (-1025 2025);
FORCEADD Q_CAPP..1
(-775 2225);
FORCEPROP 1 LAST LOCATION C7030
J 0
(-725 2325);
DISPLAY 0.787234 (-725 2325);
FORCEPROP 0 LAST $SEC 1
J 0
(-725 2375);
DISPLAY 0.680851 (-725 2375);
PAINT MONO (-725 2375);
DISPLAY INVISIBLE (-725 2375);
FORCEPROP 0 LAST CDS_SEC 1
J 0
(-725 2375);
DISPLAY 0.680851 (-725 2375);
DISPLAY INVISIBLE (-725 2375);
FORCEPROP 1 LASTPIN (-775 2325) $PN 1
J 0
(-765 2310);
DISPLAY 0.787234 (-765 2310);
PAINT MONO (-765 2310);
FORCEPROP 1 LASTPIN (-775 2125) $PN 2
J 0
(-765 2110);
DISPLAY 0.787234 (-765 2110);
PAINT MONO (-765 2110);
FORCEPROP 1 LAST PACK_TYPE SMLF
J 0
(-725 2075);
DISPLAY 0.510638 (-725 2075);
FORCEPROP 1 LAST VALUE 470UF
J 0
(-725 2275);
DISPLAY 0.510638 (-725 2275);
FORCEPROP 1 LAST MATERIAL SPCAP
J 0
(-725 2125);
DISPLAY 0.510638 (-725 2125);
FORCEPROP 1 LAST VOLTAGE 2.5V
J 0
(-725 2175);
DISPLAY 0.510638 (-725 2175);
FORCEPROP 1 LAST TOLERANCE 20%
J 0
(-725 2225);
DISPLAY 0.510638 (-725 2225);
FORCEPROP 2 LAST CDS_LIB pure_quanta
J 0
(-775 2225);
DISPLAY INVISIBLE (-775 2225);
FORCEPROP 1 LAST PATH I95
J 0
(-725 2375);
DISPLAY 0.978723 (-725 2375);
DISPLAY INVISIBLE (-725 2375);
FORCEPROP 1 LAST PART_NUMBER CH747LM8818
J 0
(-725 2025);
DISPLAY 0.404255 (-725 2025);
DISPLAY INVISIBLE (-725 2025);
FORCEADD Q_CAP..1
(-475 2225);
FORCEPROP 1 LAST LOCATION C7031
J 0
(-425 2325);
DISPLAY 0.638298 (-425 2325);
FORCEPROP 0 LAST $SEC 1
J 0
(-425 2375);
DISPLAY 0.680851 (-425 2375);
PAINT MONO (-425 2375);
DISPLAY INVISIBLE (-425 2375);
FORCEPROP 0 LAST CDS_SEC 1
J 0
(-425 2375);
DISPLAY 0.680851 (-425 2375);
DISPLAY INVISIBLE (-425 2375);
FORCEPROP 1 LASTPIN (-475 2325) $PN 1
J 0
(-465 2305);
DISPLAY 0.787234 (-465 2305);
PAINT MONO (-465 2305);
FORCEPROP 1 LASTPIN (-475 2125) $PN 2
J 0
(-465 2105);
DISPLAY 0.787234 (-465 2105);
PAINT MONO (-465 2105);
FORCEPROP 1 LAST VALUE 100UF
J 0
(-425 2275);
DISPLAY 0.638298 (-425 2275);
FORCEPROP 1 LAST VOLTAGE 4V
J 0
(-425 2225);
DISPLAY 0.638298 (-425 2225);
FORCEPROP 1 LAST PACK_TYPE C0805
J 0
(-425 2025);
DISPLAY 0.638298 (-425 2025);
FORCEPROP 1 LAST MATERIAL X6S
J 0
(-425 2125);
DISPLAY 0.638298 (-425 2125);
FORCEPROP 1 LAST TOLERANCE 20%
J 0
(-425 2175);
DISPLAY 0.638298 (-425 2175);
FORCEPROP 2 LAST CDS_LIB pure_quanta
J 0
(-475 2225);
DISPLAY INVISIBLE (-475 2225);
FORCEPROP 1 LAST PATH I96
J 0
(-425 2375);
DISPLAY 0.978723 (-425 2375);
PAINT WHITE (-425 2375);
DISPLAY INVISIBLE (-425 2375);
FORCEPROP 1 LAST PART_NUMBER CH710KMEA01
J 0
(-425 2075);
DISPLAY 0.638298 (-425 2075);
DISPLAY INVISIBLE (-425 2075);
FORCEADD DNS..2
(-7675 3675);
PAINT RED (-7675 3675);
FORCEPROP 2 LAST CDS_LIB mstr_misc
J 0
(-7675 3675);
DISPLAY INVISIBLE (-7675 3675);
FORCEPROP 1 LAST COMMENT_BODY TRUE
J 0
(-7675 3675);
DISPLAY INVISIBLE (-7675 3675);
FORCEADD CAD_NOTE..1
(-8150 2900);
FORCEPROP 0 LAST S1 L33/R897 COLAY WITH R893/R894
J 0
(-8275 2775);
DISPLAY 0.808511 (-8275 2775);
PAINT WHITE (-8275 2775);
FORCEPROP 2 LAST CDS_LIB pure_quanta_power
J 0
(-8150 2900);
DISPLAY INVISIBLE (-8150 2900);
FORCEPROP 1 LAST COMMENT_BODY TRUE
J 0
(-8125 3000);
DISPLAY 0.978723 (-8125 3000);
DISPLAY INVISIBLE (-8125 3000);
FORCEADD DNS..2
(-7675 3500);
PAINT RED (-7675 3500);
FORCEPROP 2 LAST CDS_LIB mstr_misc
J 0
(-7675 3500);
DISPLAY INVISIBLE (-7675 3500);
FORCEPROP 1 LAST COMMENT_BODY TRUE
J 0
(-7675 3500);
DISPLAY INVISIBLE (-7675 3500);
FORCEADD CAD_NOTE..1
(-5100 2400);
FORCEPROP 0 LAST S1 R705 AND R712 COLAY
J 0
(-5225 2275);
DISPLAY 0.808511 (-5225 2275);
PAINT WHITE (-5225 2275);
FORCEPROP 2 LAST CDS_LIB pure_quanta_power
J 0
(-5100 2400);
DISPLAY INVISIBLE (-5100 2400);
FORCEPROP 1 LAST COMMENT_BODY TRUE
J 0
(-5075 2500);
DISPLAY 0.978723 (-5075 2500);
DISPLAY INVISIBLE (-5075 2500);
FORCEADD DNS..2
(-4350 2700);
PAINT RED (-4350 2700);
FORCEPROP 2 LAST CDS_LIB mstr_misc
J 0
(-4350 2700);
DISPLAY INVISIBLE (-4350 2700);
FORCEPROP 1 LAST COMMENT_BODY TRUE
J 0
(-4350 2700);
DISPLAY INVISIBLE (-4350 2700);
FORCEADD QUANTA_TITLE_BLOCK_C..1
(0 0);
FORCEPROP 0 LAST CDS_CON_LAST_MODIFIED Thu Sep 14 16:13:07 2023
J 0
(-1885 15);
DISPLAY INVISIBLE (-1885 15);
FORCEPROP 1 LAST CUSTOM_TXT_CDS <CON_LAST_MODIFIED>
J 0
(-1885 15);
DISPLAY 0.978723 (-1885 15);
FORCEPROP 2 LAST CUSTOM_TXT_CDS <XR_PAGE_TITLE>
J 0
(-7890 5250);
DISPLAY 0.638298 (-7890 5250);
PAINT PINK (-7890 5250);
DISPLAY INVISIBLE (-7890 5250);
FORCEPROP 1 LAST CUSTOM_TXT_CDS <NAME_2>
J 0
(-3175 50);
FORCEPROP 1 LAST CUSTOM_TXT_CDS <NAME_1>
J 0
(-3175 175);
FORCEPROP 1 LAST CUSTOM_TXT_CDS <Q_NUMBER>
J 0
(-1403 103);
DISPLAY 1.212766 (-1403 103);
FORCEPROP 1 LAST CUSTOM_TXT_CDS <Q_PROJ>
J 0
(-2382 102);
DISPLAY 1.212766 (-2382 102);
FORCEPROP 1 LAST CUSTOM_TXT_CDS <Q_REV>
J 0
(-184 103);
DISPLAY 1.212766 (-184 103);
FORCEPROP 1 LAST CUSTOM_TXT_CDS <CON_PAGE_NUM> OF <CON_TOTAL_PAGES>
J 0
(-446 18);
DISPLAY 0.978723 (-446 18);
FORCEPROP 1 LAST Q_TITLE RETIMER_CPU1_P3 DECAPS(8)
J 0
(-9366 26);
DISPLAY 2.446809 (-9366 26);
PAINT GREEN (-9366 26);
FORCEPROP 2 LAST PAGE_BORDER TRUE
J 0
(-7890 5250);
DISPLAY 0.638298 (-7890 5250);
PAINT PINK (-7890 5250);
DISPLAY INVISIBLE (-7890 5250);
FORCEPROP 1 LAST CDS_LMAN_SYM_OUTLINE -9475,6775,100,-125
J 0
(0 0);
DISPLAY 0.468085 (0 0);
PAINT GREEN (0 0);
DISPLAY INVISIBLE (0 0);
FORCEPROP 2 LAST CDS_LIB pure_quanta
J 0
(0 0);
DISPLAY INVISIBLE (0 0);
FORCEPROP 2 LAST CDS_XR_PAGE_TITLE CR-357 : @T6G_MB_LIB.T6G(SCH_1):PAGE357
J 0
(-7890 5250);
DISPLAY 0.638298 (-7890 5250);
PAINT PINK (-7890 5250);
DISPLAY INVISIBLE (-7890 5250);
FORCEPROP 1 LAST Q_DEPT BU9
J 1
(-3763 49);
DISPLAY 1.957447 (-3763 49);
PAINT GREEN (-3763 49);
DISPLAY INVISIBLE (-3763 49);
FORCEPROP 1 LAST COMMENT_BODY TRUE
J 0
(12 -13);
DISPLAY 0.978723 (12 -13);
PAINT GREEN (12 -13);
DISPLAY INVISIBLE (12 -13);
FORCEADD DNS..2
(-8025 4025);
PAINT RED (-8025 4025);
FORCEPROP 2 LAST CDS_LIB mstr_misc
J 0
(-8025 4025);
DISPLAY INVISIBLE (-8025 4025);
FORCEPROP 1 LAST COMMENT_BODY TRUE
J 0
(-8025 4025);
DISPLAY INVISIBLE (-8025 4025);
WIRE 16 -1 (-1400 5650)(-1125 5650);
WIRE 16 -1 (-1400 5650)(-1400 5475);
WIRE 16 -1 (-1650 5650)(-1400 5650);
WIRE 16 -1 (-1125 5650)(-1125 5475);
WIRE 16 -1 (-1925 5650)(-1650 5650);
WIRE 16 -1 (-1650 5475)(-1650 5650);
WIRE 16 -1 (-1925 5650)(-1925 5475);
WIRE 16 -1 (-2225 5650)(-1925 5650);
WIRE 16 -1 (-2525 5650)(-2225 5650);
WIRE 16 -1 (-2225 5650)(-2225 5500);
WIRE 16 -1 (-2525 5650)(-2525 5500);
WIRE 16 -1 (-2825 5650)(-2525 5650);
WIRE 16 -1 (-2825 5650)(-2825 5500);
WIRE 16 -1 (-3150 5650)(-2825 5650);
WIRE 16 -1 (-3425 5650)(-3150 5650);
WIRE 16 -1 (-3150 5650)(-3150 5525);
WIRE 16 -1 (-3425 5650)(-3425 5525);
WIRE 16 -1 (-4300 5650)(-3425 5650);
WIRE 16 -1 (-4300 5875)(-4300 5650);
WIRE 16 -1 (-4300 4400)(-4300 5650);
WIRE 16 -1 (-3925 4400)(-4300 4400);
WIRE 16 -1 (-4300 4400)(-4300 2825);
WIRE 16 -1 (-1125 5275)(-1125 5100);
WIRE 16 -1 (-1125 5100)(-1200 5100);
WIRE 16 -1 (-1200 5100)(-1400 5100);
WIRE 16 -1 (-1200 5100)(-1200 5025);
WIRE 16 -1 (-1400 5275)(-1400 5100);
WIRE 16 -1 (-1650 5100)(-1400 5100);
WIRE 16 -1 (-1650 5275)(-1650 5100);
WIRE 16 -1 (-1925 5100)(-1650 5100);
WIRE 16 -1 (-1925 5275)(-1925 5100);
WIRE 16 -1 (-1925 5100)(-2225 5100);
WIRE 16 -1 (-2225 5300)(-2225 5100);
WIRE 16 -1 (-2525 5100)(-2225 5100);
WIRE 16 -1 (-2525 5300)(-2525 5100);
WIRE 16 -1 (-2825 5100)(-2525 5100);
WIRE 16 -1 (-2825 5300)(-2825 5100);
WIRE 16 -1 (-3150 5100)(-2825 5100);
WIRE 16 -1 (-3150 5325)(-3150 5100);
WIRE 16 -1 (-3425 5100)(-3150 5100);
WIRE 16 -1 (-3425 5325)(-3425 5100);
WIRE 16 -1 (-475 2450)(-475 2325);
WIRE 16 -1 (-775 2450)(-475 2450);
WIRE 16 -1 (-775 2325)(-775 2450);
WIRE 16 -1 (-1075 2450)(-775 2450);
WIRE 16 -1 (-1075 2325)(-1075 2450);
WIRE 16 -1 (-1375 2450)(-1075 2450);
WIRE 16 -1 (-1375 2300)(-1375 2450);
WIRE 16 -1 (-1375 2450)(-1625 2450);
WIRE 16 -1 (-1625 2300)(-1625 2450);
WIRE 16 -1 (-1900 2450)(-1625 2450);
WIRE 16 -1 (-1900 2300)(-1900 2450);
WIRE 16 -1 (-2175 2450)(-1900 2450);
WIRE 16 -1 (-2175 2300)(-2175 2450);
WIRE 16 -1 (-2425 2450)(-2175 2450);
WIRE 16 -1 (-2425 2300)(-2425 2450);
WIRE 16 -1 (-2675 2450)(-2425 2450);
WIRE 16 -1 (-2675 2450)(-2675 2300);
WIRE 16 -1 (-2900 2450)(-2675 2450);
WIRE 16 -1 (-2900 2450)(-2900 2300);
WIRE 16 -1 (-3200 2450)(-2900 2450);
WIRE 16 -1 (-3200 2450)(-3200 2300);
WIRE 16 -1 (-3650 2450)(-3200 2450);
WIRE 16 -1 (-3650 3125)(-3650 2450);
WIRE 16 -1 (-3650 2450)(-3825 2450);
WIRE 16 -1 (-3650 3125)(-3475 3125);
WIRE 16 -1 (-3650 3750)(-3650 3125);
WIRE 16 -1 (-3650 4400)(-3650 3750);
WIRE 16 -1 (-3650 3750)(-3475 3750);
WIRE 16 -1 (-3475 3125)(-3250 3125);
WIRE 16 -1 (-3475 3125)(-3475 3000);
WIRE 16 -1 (-3250 3125)(-3000 3125);
WIRE 16 -1 (-3250 3125)(-3250 3000);
WIRE 16 -1 (-3475 3750)(-3250 3750);
WIRE 16 -1 (-3475 3625)(-3475 3750);
WIRE 16 -1 (-3650 4400)(-3475 4400);
WIRE 16 -1 (-3725 4400)(-3650 4400);
WIRE 16 -1 (-3475 4750)(-3475 4400);
WIRE 16 -1 (-3475 4400)(-3250 4400);
WIRE 16 -1 (-3475 4400)(-3475 4250);
WIRE 16 -1 (-3250 3750)(-3025 3750);
WIRE 16 -1 (-3250 3625)(-3250 3750);
WIRE 16 -1 (-3000 3125)(-2775 3125);
WIRE 16 -1 (-3000 3125)(-3000 3000);
WIRE 16 -1 (-2775 3125)(-2525 3125);
WIRE 16 -1 (-2775 3125)(-2775 3000);
WIRE 16 -1 (-3025 3750)(-2800 3750);
WIRE 16 -1 (-3025 3625)(-3025 3750);
WIRE 16 -1 (-3025 4400)(-3250 4400);
WIRE 16 -1 (-3250 4400)(-3250 4250);
WIRE 16 -1 (-2800 4400)(-3025 4400);
WIRE 16 -1 (-3025 4400)(-3025 4250);
WIRE 16 -1 (-2800 3750)(-2550 3750);
WIRE 16 -1 (-2800 3625)(-2800 3750);
WIRE 16 -1 (-2525 3125)(-2300 3125);
WIRE 16 -1 (-2525 3125)(-2525 3000);
WIRE 16 -1 (-2300 3125)(-2075 3125);
WIRE 16 -1 (-2300 3125)(-2300 2975);
WIRE 16 -1 (-2550 3750)(-2325 3750);
WIRE 16 -1 (-2550 3625)(-2550 3750);
WIRE 16 -1 (-2550 4400)(-2800 4400);
WIRE 16 -1 (-2800 4400)(-2800 4250);
WIRE 16 -1 (-2325 4400)(-2550 4400);
WIRE 16 -1 (-2550 4400)(-2550 4250);
WIRE 16 -1 (-2325 3750)(-2100 3750);
WIRE 16 -1 (-2325 3625)(-2325 3750);
WIRE 16 -1 (-1850 3125)(-2075 3125);
WIRE 16 -1 (-2075 2975)(-2075 3125);
WIRE 16 -1 (-1850 3125)(-1600 3125);
WIRE 16 -1 (-1850 2975)(-1850 3125);
WIRE 16 -1 (-2100 3750)(-1875 3750);
WIRE 16 -1 (-2100 3625)(-2100 3750);
WIRE 16 -1 (-2100 4400)(-2325 4400);
WIRE 16 -1 (-2325 4400)(-2325 4250);
WIRE 16 -1 (-1875 4400)(-2100 4400);
WIRE 16 -1 (-2100 4400)(-2100 4250);
WIRE 16 -1 (-1875 3750)(-1650 3750);
WIRE 16 -1 (-1875 3625)(-1875 3750);
WIRE 16 -1 (-1600 3125)(-1600 2975);
WIRE 16 -1 (-1400 3750)(-1650 3750);
WIRE 16 -1 (-1650 3625)(-1650 3750);
WIRE 16 -1 (-1575 4400)(-1875 4400);
WIRE 16 -1 (-1875 4400)(-1875 4250);
WIRE 16 -1 (-1575 4400)(-1275 4400);
WIRE 16 -1 (-1575 4400)(-1575 4250);
WIRE 16 -1 (-1400 3750)(-1400 3625);
WIRE 16 -1 (-1275 4400)(-1275 4250);
WIRE 16 -1 (-3475 3425)(-3475 3300);
WIRE 16 -1 (-3475 3300)(-3250 3300);
WIRE 16 -1 (-3250 3300)(-3025 3300);
WIRE 16 -1 (-3250 3425)(-3250 3300);
WIRE 16 -1 (-3025 3300)(-2800 3300);
WIRE 16 -1 (-3025 3425)(-3025 3300);
WIRE 16 -1 (-2800 3300)(-2550 3300);
WIRE 16 -1 (-2800 3425)(-2800 3300);
WIRE 16 -1 (-2550 3425)(-2550 3300);
WIRE 16 -1 (-2550 3300)(-2325 3300);
WIRE 16 -1 (-2325 3300)(-2100 3300);
WIRE 16 -1 (-2325 3425)(-2325 3300);
WIRE 16 -1 (-2100 3300)(-1875 3300);
WIRE 16 -1 (-2100 3425)(-2100 3300);
WIRE 16 -1 (-1875 3300)(-1650 3300);
WIRE 16 -1 (-1875 3425)(-1875 3300);
WIRE 16 -1 (-1400 3300)(-1650 3300);
WIRE 16 -1 (-1650 3425)(-1650 3300);
WIRE 16 -1 (-875 3300)(-1400 3300);
WIRE 16 -1 (-1400 3425)(-1400 3300);
WIRE 16 -1 (-875 3900)(-875 3300);
WIRE 16 -1 (-875 3300)(-875 2575);
WIRE 16 -1 (-875 2575)(-1600 2575);
WIRE 16 -1 (-875 2575)(-875 2525);
WIRE 16 -1 (-875 3900)(-1275 3900);
WIRE 16 -1 (-1275 4050)(-1275 3900);
WIRE 16 -1 (-1275 3900)(-1575 3900);
WIRE 16 -1 (-1850 2575)(-1600 2575);
WIRE 16 -1 (-1600 2775)(-1600 2575);
WIRE 16 -1 (-1850 2775)(-1850 2575);
WIRE 16 -1 (-1850 2575)(-2075 2575);
WIRE 16 -1 (-1575 4050)(-1575 3900);
WIRE 16 -1 (-1575 3900)(-1875 3900);
WIRE 16 -1 (-1875 4050)(-1875 3900);
WIRE 16 -1 (-1875 3900)(-2100 3900);
WIRE 16 -1 (-2075 2775)(-2075 2575);
WIRE 16 -1 (-2300 2575)(-2075 2575);
WIRE 16 -1 (-2300 2775)(-2300 2575);
WIRE 16 -1 (-2525 2575)(-2300 2575);
WIRE 16 -1 (-2100 4050)(-2100 3900);
WIRE 16 -1 (-2100 3900)(-2325 3900);
WIRE 16 -1 (-2325 4050)(-2325 3900);
WIRE 16 -1 (-2325 3900)(-2550 3900);
WIRE 16 -1 (-2525 2800)(-2525 2575);
WIRE 16 -1 (-2775 2575)(-2525 2575);
WIRE 16 -1 (-2775 2800)(-2775 2575);
WIRE 16 -1 (-3000 2575)(-2775 2575);
WIRE 16 -1 (-2550 4050)(-2550 3900);
WIRE 16 -1 (-2550 3900)(-2800 3900);
WIRE 16 -1 (-2800 4050)(-2800 3900);
WIRE 16 -1 (-3025 3900)(-2800 3900);
WIRE 16 -1 (-3000 2800)(-3000 2575);
WIRE 16 -1 (-3250 2575)(-3000 2575);
WIRE 16 -1 (-3250 2800)(-3250 2575);
WIRE 16 -1 (-3475 2575)(-3250 2575);
WIRE 16 -1 (-3025 4050)(-3025 3900);
WIRE 16 -1 (-3250 3900)(-3025 3900);
WIRE 16 -1 (-3250 4050)(-3250 3900);
WIRE 16 -1 (-3475 3900)(-3250 3900);
WIRE 16 -1 (-3475 2800)(-3475 2575);
WIRE 16 -1 (-3475 4050)(-3475 3900);
WIRE 16 -1 (-8100 4250)(-8100 4150);
WIRE 16 -1 (-8150 4250)(-8100 4250);
WIRE 16 -1 (-8150 4400)(-8150 4250);
WIRE 16 -1 (-8150 4250)(-8200 4250);
WIRE 16 -1 (-8200 4250)(-8200 4175);
WIRE 16 -1 (-8150 5125)(-8150 4400);
WIRE 16 -1 (-8150 4400)(-7875 4400);
WIRE 16 -1 (-7050 5125)(-8150 5125);
WIRE 16 -1 (-8150 5200)(-8150 5125);
WIRE 16 -1 (-7050 5125)(-6800 5125);
WIRE 16 -1 (-7050 5125)(-7050 5075);
WIRE 16 -1 (-6800 5125)(-6550 5125);
WIRE 16 -1 (-6800 5125)(-6800 5075);
WIRE 16 -1 (-6550 5125)(-6300 5125);
WIRE 16 -1 (-6550 5125)(-6550 5050);
WIRE 16 -1 (-6300 5125)(-6300 5050);
WIRE 16 -1 (-6300 4850)(-6300 4725);
WIRE 16 -1 (-6375 4725)(-6300 4725);
WIRE 16 -1 (-6550 4725)(-6375 4725);
WIRE 16 -1 (-6550 4850)(-6550 4725);
WIRE 16 -1 (-6800 4725)(-6550 4725);
WIRE 16 -1 (-6800 4875)(-6800 4725);
WIRE 16 -1 (-7050 4725)(-6800 4725);
WIRE 16 -1 (-7050 4875)(-7050 4725);
WIRE 16 -1 (-5150 4400)(-5150 4250);
WIRE 16 -1 (-5150 4400)(-5425 4400);
WIRE 16 -1 (-5425 4400)(-5425 4250);
WIRE 16 -1 (-5425 4400)(-5675 4400);
WIRE 16 -1 (-5675 4400)(-5675 4250);
WIRE 16 -1 (-5675 4400)(-5925 4400);
WIRE 16 -1 (-5925 4400)(-5925 4250);
WIRE 16 -1 (-6150 4400)(-5925 4400);
WIRE 16 -1 (-6150 4400)(-6350 4400);
WIRE 16 -1 (-6150 4400)(-6150 4250);
WIRE 16 -1 (-6350 4400)(-6350 4250);
WIRE 16 -1 (-6350 4400)(-6575 4400);
WIRE 16 -1 (-6575 4400)(-6575 4250);
WIRE 16 -1 (-6775 4400)(-6575 4400);
WIRE 16 -1 (-6775 4400)(-6775 4250);
WIRE 16 -1 (-6775 4400)(-6975 4400);
WIRE 16 -1 (-6975 4400)(-6975 4250);
WIRE 16 -1 (-7200 4400)(-6975 4400);
WIRE 16 -1 (-7200 4400)(-7300 4400);
WIRE 16 -1 (-7200 4400)(-7200 4250);
WIRE 16 -1 (-7300 4575)(-7300 4400);
WIRE 16 -1 (-7300 4400)(-7675 4400);
WIRE 16 -1 (-7300 3625)(-7300 4400);
WIRE 16 -1 (-7400 3625)(-7300 3625);
WIRE 16 -1 (-7400 3725)(-7400 3625);
WIRE 16 -1 (-7400 3625)(-7400 3525);
WIRE 16 -1 (-7600 3525)(-7400 3525);
WIRE 16 -1 (-7600 3725)(-7400 3725);
WIRE 16 -1 (-5150 4050)(-5150 3950);
WIRE 16 -1 (-5425 3950)(-5150 3950);
WIRE 16 -1 (-5425 4050)(-5425 3950);
WIRE 16 -1 (-5675 3950)(-5425 3950);
WIRE 16 -1 (-5675 4050)(-5675 3950);
WIRE 16 -1 (-5925 3950)(-5675 3950);
WIRE 16 -1 (-5925 4050)(-5925 3950);
WIRE 16 -1 (-6150 3950)(-5925 3950);
WIRE 16 -1 (-6350 3950)(-6150 3950);
WIRE 16 -1 (-6150 4050)(-6150 3950);
WIRE 16 -1 (-6150 3950)(-6150 3875);
WIRE 16 -1 (-6350 4050)(-6350 3950);
WIRE 16 -1 (-6575 3950)(-6350 3950);
WIRE 16 -1 (-6575 4050)(-6575 3950);
WIRE 16 -1 (-6775 3950)(-6575 3950);
WIRE 16 -1 (-6775 4050)(-6775 3950);
WIRE 16 -1 (-6975 3950)(-6775 3950);
WIRE 16 -1 (-6975 4050)(-6975 3950);
WIRE 16 -1 (-7200 3950)(-6975 3950);
WIRE 16 -1 (-7200 4050)(-7200 3950);
WIRE 16 -1 (-3200 2100)(-3200 1975);
WIRE 16 -1 (-3200 1975)(-2900 1975);
WIRE 16 -1 (-2900 2100)(-2900 1975);
WIRE 16 -1 (-2900 1975)(-2675 1975);
WIRE 16 -1 (-2675 2100)(-2675 1975);
WIRE 16 -1 (-2675 1975)(-2425 1975);
WIRE 16 -1 (-2425 2100)(-2425 1975);
WIRE 16 -1 (-2425 1975)(-2175 1975);
WIRE 16 -1 (-2175 1975)(-1900 1975);
WIRE 16 -1 (-2175 2100)(-2175 1975);
WIRE 16 -1 (-1900 2100)(-1900 1975);
WIRE 16 -1 (-1625 1975)(-1900 1975);
WIRE 16 -1 (-1625 2100)(-1625 1975);
WIRE 16 -1 (-1625 1975)(-1375 1975);
WIRE 16 -1 (-1075 1975)(-1375 1975);
WIRE 16 -1 (-1375 2100)(-1375 1975);
WIRE 16 -1 (-1375 1975)(-1375 1825);
WIRE 16 -1 (-1075 2125)(-1075 1975);
WIRE 16 -1 (-775 1975)(-1075 1975);
WIRE 16 -1 (-775 2125)(-775 1975);
WIRE 16 -1 (-475 1975)(-775 1975);
WIRE 16 -1 (-475 2125)(-475 1975);
WIRE 16 -1 (-6775 2975)(-6775 2800);
WIRE 16 -1 (-6775 2800)(-6500 2800);
WIRE 16 -1 (-6500 2950)(-6500 2800);
WIRE 16 -1 (-6500 2800)(-6500 2700);
WIRE 16 -1 (-4300 2625)(-4300 2450);
WIRE 16 -1 (-4300 2450)(-4025 2450);
WIRE 16 -1 (-4300 1350)(-4300 2450);
WIRE 16 -1 (-4300 1350)(-3150 1350);
WIRE 16 -1 (-3025 1350)(-3150 1350);
WIRE 16 -1 (-3150 1575)(-3150 1350);
WIRE 16 -1 (-2775 1350)(-3025 1350);
WIRE 16 -1 (-3025 1350)(-3025 1200);
WIRE 16 -1 (-2475 1350)(-2775 1350);
WIRE 16 -1 (-2775 1350)(-2775 1200);
WIRE 16 -1 (-2225 1350)(-2475 1350);
WIRE 16 -1 (-2475 1200)(-2475 1350);
WIRE 16 -1 (-2225 1200)(-2225 1350);
WIRE 16 -1 (-3025 1000)(-3025 875);
WIRE 16 -1 (-3025 875)(-2775 875);
WIRE 16 -1 (-2775 875)(-2475 875);
WIRE 16 -1 (-2775 1000)(-2775 875);
WIRE 16 -1 (-2475 875)(-2325 875);
WIRE 16 -1 (-2475 1000)(-2475 875);
WIRE 16 -1 (-2225 875)(-2325 875);
WIRE 16 -1 (-2325 875)(-2325 825);
WIRE 16 -1 (-2225 1000)(-2225 875);
WIRE 16 -1 (-8100 3800)(-8100 3950);
WIRE 16 -1 (-8150 3800)(-8100 3800);
WIRE 16 -1 (-8150 3625)(-8150 3800);
WIRE 16 -1 (-8200 3800)(-8150 3800);
WIRE 16 -1 (-8200 3800)(-8200 3975);
WIRE 16 -1 (-8150 3625)(-8050 3625);
WIRE 16 -1 (-8150 3300)(-8150 3625);
WIRE 16 -1 (-8150 3300)(-6900 3300);
WIRE 16 -1 (-8050 3725)(-8050 3625);
WIRE 16 -1 (-8050 3625)(-8050 3525);
WIRE 16 -1 (-8050 3525)(-7800 3525);
WIRE 16 -1 (-7800 3725)(-8050 3725);
WIRE 16 -1 (-6775 3300)(-6900 3300);
WIRE 16 -1 (-6900 3300)(-6900 3400);
WIRE 16 -1 (-6775 3300)(-6500 3300);
WIRE 16 -1 (-6775 3175)(-6775 3300);
WIRE 16 -1 (-6500 3300)(-6500 3150);
DOT 1 (-2550 3300);
DOT 1 (-775 1975);
DOT 1 (-775 2450);
DOT 1 (-1075 1975);
DOT 1 (-1075 2450);
DOT 1 (-1375 1975);
DOT 1 (-1375 2450);
DOT 1 (-8150 3625);
DOT 1 (-8050 3625);
DOT 1 (-8150 3800);
DOT 1 (-7400 3625);
DOT 1 (-6500 2800);
DOT 1 (-6900 3300);
DOT 1 (-6775 3300);
DOT 1 (-4300 2450);
DOT 1 (-8150 4250);
DOT 1 (-7300 4400);
DOT 1 (-6975 3950);
DOT 1 (-7200 4400);
DOT 1 (-6975 4400);
DOT 1 (-6775 3950);
DOT 1 (-6800 4725);
DOT 1 (-6575 4400);
DOT 1 (-6350 3950);
DOT 1 (-6550 4725);
DOT 1 (-7050 5125);
DOT 1 (-6800 5125);
DOT 1 (-6550 5125);
DOT 1 (-6150 3950);
DOT 1 (-5925 3950);
DOT 1 (-5675 4400);
DOT 1 (-5675 3950);
DOT 1 (-5425 3950);
DOT 1 (-4300 4400);
DOT 1 (-4300 5650);
DOT 1 (-3150 1350);
DOT 1 (-2475 1350);
DOT 1 (-2325 875);
DOT 1 (-3650 2450);
DOT 1 (-3200 2450);
DOT 1 (-3250 2575);
DOT 1 (-3650 3750);
DOT 1 (-3650 3125);
DOT 1 (-3250 3125);
DOT 1 (-3250 3300);
DOT 1 (-3475 3750);
DOT 1 (-3250 3750);
DOT 1 (-3250 3900);
DOT 1 (-2900 1975);
DOT 1 (-2675 1975);
DOT 1 (-3000 2575);
DOT 1 (-2675 2450);
DOT 1 (-2775 2575);
DOT 1 (-2425 1975);
DOT 1 (-2525 2575);
DOT 1 (-2425 2450);
DOT 1 (-2175 2450);
DOT 1 (-3025 3300);
DOT 1 (-2800 3300);
DOT 1 (-3025 3750);
DOT 1 (-2800 3900);
DOT 1 (-2325 3300);
DOT 1 (-2100 3300);
DOT 1 (-2550 3900);
DOT 1 (-1900 2450);
DOT 1 (-1875 3750);
DOT 1 (-1650 3750);
DOT 1 (-1575 3900);
DOT 1 (-1275 3900);
DOT 1 (-875 3300);
DOT 1 (-3650 4400);
DOT 1 (-3475 4400);
DOT 1 (-3150 5100);
DOT 1 (-3425 5650);
DOT 1 (-3150 5650);
DOT 1 (-2825 5100);
DOT 1 (-2825 5650);
DOT 1 (-2525 5100);
DOT 1 (-2525 5650);
DOT 1 (-1575 4400);
DOT 1 (-1650 5100);
DOT 1 (-1925 5650);
DOT 1 (-1400 5100);
DOT 1 (-1200 5100);
DOT 1 (-8150 5125);
DOT 1 (-8150 4400);
DOT 1 (-5925 4400);
DOT 1 (-6775 4400);
DOT 1 (-6350 4400);
DOT 1 (-5425 4400);
DOT 1 (-6150 4400);
DOT 1 (-6575 3950);
DOT 1 (-2225 5650);
DOT 1 (-1400 5650);
DOT 1 (-1650 5650);
DOT 1 (-1925 5100);
DOT 1 (-3025 4400);
DOT 1 (-3250 4400);
DOT 1 (-2800 4400);
DOT 1 (-2100 4400);
DOT 1 (-2325 4400);
DOT 1 (-2550 4400);
DOT 1 (-1875 3900);
DOT 1 (-2300 3125);
DOT 1 (-2075 3125);
DOT 1 (-875 2575);
DOT 1 (-2300 2575);
DOT 1 (-2225 5100);
DOT 1 (-2100 3900);
DOT 1 (-2100 3750);
DOT 1 (-1875 4400);
DOT 1 (-3025 3900);
DOT 1 (-2325 3900);
DOT 1 (-2325 3750);
DOT 1 (-2800 3750);
DOT 1 (-2900 2450);
DOT 1 (-1400 3300);
DOT 1 (-2550 3750);
DOT 1 (-3000 3125);
DOT 1 (-1875 3300);
DOT 1 (-2775 3125);
DOT 1 (-2075 2575);
DOT 1 (-1650 3300);
DOT 1 (-1625 1975);
DOT 1 (-2525 3125);
DOT 1 (-3475 3125);
DOT 1 (-2175 1975);
DOT 1 (-1900 1975);
DOT 1 (-1600 2575);
DOT 1 (-1850 3125);
DOT 1 (-1850 2575);
DOT 1 (-1625 2450);
DOT 1 (-2475 875);
DOT 1 (-3025 1350);
DOT 1 (-2775 1350);
DOT 1 (-2775 875);
QUIT
